FILE_TYPE = MACRO_DRAWING;
SET COLOR_WIRE YELLOW;
SET COLOR_PROP MONO;
SET COLOR_DOT WHITE;
SET COLOR_ARC YELLOW;
SET COLOR_BODY GREEN;
SET COLOR_NOTE MONO;
SET PROP_DISPLAY VALUE;
SET PAGE_NUMBER P85;
FORCEADD OFFPAGE..3
(1600 5200);
FORCEPROP 2 LAST $XR1 86 
J 0
(1904 5200);
DISPLAY 0.638298 (1904 5200);
PAINT MONO (1904 5200);
FORCEPROP 2 LAST $XR0 61 
J 0
(1814 5200);
DISPLAY 0.638298 (1814 5200);
PAINT MONO (1814 5200);
FORCEPROP 2 LAST CDS_LIB mstr_standard
J 0
(1600 5200);
DISPLAY 0.787234 (1600 5200);
PAINT MONO (1600 5200);
DISPLAY INVISIBLE (1600 5200);
FORCEPROP 1 LAST OFFPAGE TRUE
J 0
(1925 5075);
DISPLAY 0.936170 (1925 5075);
PAINT GREEN (1925 5075);
DISPLAY INVISIBLE (1925 5075);
FORCEPROP 1 LAST COMMENT_BODY TRUE
J 0
(1550 5100);
DISPLAY 0.936170 (1550 5100);
PAINT GREEN (1550 5100);
DISPLAY INVISIBLE (1550 5100);
FORCEPROP 2 LAST PATH I1
J 0
(1800 5275);
DISPLAY 0.787234 (1800 5275);
PAINT MONO (1800 5275);
DISPLAY INVISIBLE (1800 5275);
FORCEADD TAP..6
R 2
(700 4850);
FORCEPROP 3 LASTPIN (650 4850) SIG_NAME M_L_DQS_DP<14>
J 0
(660 4860);
DISPLAY 0.659574 (660 4860);
PAINT MONO (660 4860);
DISPLAY INVISIBLE (660 4860);
FORCEPROP 1 LASTPIN (650 4850) BN 14
J 2
(700 4860);
DISPLAY 0.617021 (700 4860);
PAINT PINK (700 4860);
FORCEPROP 2 LAST CDS_LIB mstr_standard
J 0
(700 4850);
DISPLAY 0.787234 (700 4850);
PAINT MONO (700 4850);
DISPLAY INVISIBLE (700 4850);
FORCEPROP 1 LAST BODY_TYPE PLUMBING
J 2
(700 4800);
DISPLAY 1.234043 (700 4800);
PAINT GREEN (700 4800);
DISPLAY INVISIBLE (700 4800);
FORCEPROP 1 LAST HDL_TAP TRUE
J 2
(375 4725);
DISPLAY 1.234043 (375 4725);
PAINT GREEN (375 4725);
DISPLAY INVISIBLE (375 4725);
FORCEPROP 1 LAST PATH I10
J 2
(700 4850);
DISPLAY 0.936170 (700 4850);
PAINT GREEN (700 4850);
DISPLAY INVISIBLE (700 4850);
FORCEADD TAP..6
R 2
(-1750 2200);
FORCEPROP 3 LASTPIN (-1800 2200) SIG_NAME M_L_DQ<8>
J 0
(-1790 2210);
DISPLAY 0.659574 (-1790 2210);
PAINT MONO (-1790 2210);
DISPLAY INVISIBLE (-1790 2210);
FORCEPROP 1 LASTPIN (-1800 2200) BN 8
J 2
(-1750 2210);
DISPLAY 0.617021 (-1750 2210);
PAINT PINK (-1750 2210);
FORCEPROP 2 LAST CDS_LIB mstr_standard
J 2
(-1750 2200);
DISPLAY 0.787234 (-1750 2200);
PAINT MONO (-1750 2200);
DISPLAY INVISIBLE (-1750 2200);
FORCEPROP 1 LAST BODY_TYPE PLUMBING
J 2
(-1750 2150);
DISPLAY 1.234043 (-1750 2150);
PAINT GREEN (-1750 2150);
DISPLAY INVISIBLE (-1750 2150);
FORCEPROP 1 LAST HDL_TAP TRUE
J 2
(-2075 2075);
DISPLAY 1.234043 (-2075 2075);
PAINT GREEN (-2075 2075);
DISPLAY INVISIBLE (-2075 2075);
FORCEPROP 1 LAST PATH I100
J 2
(-1750 2200);
DISPLAY 0.936170 (-1750 2200);
PAINT GREEN (-1750 2200);
DISPLAY INVISIBLE (-1750 2200);
FORCEADD TAP..6
R 2
(-1750 2250);
FORCEPROP 3 LASTPIN (-1800 2250) SIG_NAME M_L_DQ<11>
J 0
(-1790 2260);
DISPLAY 0.659574 (-1790 2260);
PAINT MONO (-1790 2260);
DISPLAY INVISIBLE (-1790 2260);
FORCEPROP 1 LASTPIN (-1800 2250) BN 11
J 2
(-1750 2260);
DISPLAY 0.617021 (-1750 2260);
PAINT PINK (-1750 2260);
FORCEPROP 2 LAST CDS_LIB mstr_standard
J 2
(-1750 2250);
DISPLAY 0.787234 (-1750 2250);
PAINT MONO (-1750 2250);
DISPLAY INVISIBLE (-1750 2250);
FORCEPROP 1 LAST BODY_TYPE PLUMBING
J 2
(-1750 2200);
DISPLAY 1.234043 (-1750 2200);
PAINT GREEN (-1750 2200);
DISPLAY INVISIBLE (-1750 2200);
FORCEPROP 1 LAST HDL_TAP TRUE
J 2
(-2075 2125);
DISPLAY 1.234043 (-2075 2125);
PAINT GREEN (-2075 2125);
DISPLAY INVISIBLE (-2075 2125);
FORCEPROP 1 LAST PATH I101
J 2
(-1750 2250);
DISPLAY 0.936170 (-1750 2250);
PAINT GREEN (-1750 2250);
DISPLAY INVISIBLE (-1750 2250);
FORCEADD TAP..6
R 2
(-1750 1950);
FORCEPROP 3 LASTPIN (-1800 1950) SIG_NAME M_L_DQ<5>
J 0
(-1790 1960);
DISPLAY 0.659574 (-1790 1960);
PAINT MONO (-1790 1960);
DISPLAY INVISIBLE (-1790 1960);
FORCEPROP 1 LASTPIN (-1800 1950) BN 5
J 2
(-1750 1960);
DISPLAY 0.617021 (-1750 1960);
PAINT PINK (-1750 1960);
FORCEPROP 2 LAST CDS_LIB mstr_standard
J 2
(-1750 1950);
DISPLAY 0.787234 (-1750 1950);
PAINT MONO (-1750 1950);
DISPLAY INVISIBLE (-1750 1950);
FORCEPROP 1 LAST BODY_TYPE PLUMBING
J 2
(-1750 1900);
DISPLAY 1.234043 (-1750 1900);
PAINT GREEN (-1750 1900);
DISPLAY INVISIBLE (-1750 1900);
FORCEPROP 1 LAST HDL_TAP TRUE
J 2
(-2075 1825);
DISPLAY 1.234043 (-2075 1825);
PAINT GREEN (-2075 1825);
DISPLAY INVISIBLE (-2075 1825);
FORCEPROP 1 LAST PATH I102
J 2
(-1750 1950);
DISPLAY 0.936170 (-1750 1950);
PAINT GREEN (-1750 1950);
DISPLAY INVISIBLE (-1750 1950);
FORCEADD TAP..6
R 2
(-1750 1900);
FORCEPROP 3 LASTPIN (-1800 1900) SIG_NAME M_L_DQ<2>
J 0
(-1790 1910);
DISPLAY 0.659574 (-1790 1910);
PAINT MONO (-1790 1910);
DISPLAY INVISIBLE (-1790 1910);
FORCEPROP 1 LASTPIN (-1800 1900) BN 2
J 2
(-1750 1910);
DISPLAY 0.617021 (-1750 1910);
PAINT PINK (-1750 1910);
FORCEPROP 2 LAST CDS_LIB mstr_standard
J 2
(-1750 1900);
DISPLAY 0.787234 (-1750 1900);
PAINT MONO (-1750 1900);
DISPLAY INVISIBLE (-1750 1900);
FORCEPROP 1 LAST BODY_TYPE PLUMBING
J 2
(-1750 1850);
DISPLAY 1.234043 (-1750 1850);
PAINT GREEN (-1750 1850);
DISPLAY INVISIBLE (-1750 1850);
FORCEPROP 1 LAST HDL_TAP TRUE
J 2
(-2075 1775);
DISPLAY 1.234043 (-2075 1775);
PAINT GREEN (-2075 1775);
DISPLAY INVISIBLE (-2075 1775);
FORCEPROP 1 LAST PATH I103
J 2
(-1750 1900);
DISPLAY 0.936170 (-1750 1900);
PAINT GREEN (-1750 1900);
DISPLAY INVISIBLE (-1750 1900);
FORCEADD TAP..6
R 2
(-1750 2000);
FORCEPROP 3 LASTPIN (-1800 2000) SIG_NAME M_L_DQ<4>
J 0
(-1790 2010);
DISPLAY 0.659574 (-1790 2010);
PAINT MONO (-1790 2010);
DISPLAY INVISIBLE (-1790 2010);
FORCEPROP 1 LASTPIN (-1800 2000) BN 4
J 2
(-1750 2010);
DISPLAY 0.617021 (-1750 2010);
PAINT PINK (-1750 2010);
FORCEPROP 2 LAST CDS_LIB mstr_standard
J 2
(-1750 2000);
DISPLAY 0.787234 (-1750 2000);
PAINT MONO (-1750 2000);
DISPLAY INVISIBLE (-1750 2000);
FORCEPROP 1 LAST BODY_TYPE PLUMBING
J 2
(-1750 1950);
DISPLAY 1.234043 (-1750 1950);
PAINT GREEN (-1750 1950);
DISPLAY INVISIBLE (-1750 1950);
FORCEPROP 1 LAST HDL_TAP TRUE
J 2
(-2075 1875);
DISPLAY 1.234043 (-2075 1875);
PAINT GREEN (-2075 1875);
DISPLAY INVISIBLE (-2075 1875);
FORCEPROP 1 LAST PATH I104
J 2
(-1750 2000);
DISPLAY 0.936170 (-1750 2000);
PAINT GREEN (-1750 2000);
DISPLAY INVISIBLE (-1750 2000);
FORCEADD TAP..6
R 2
(-1750 2050);
FORCEPROP 3 LASTPIN (-1800 2050) SIG_NAME M_L_DQ<7>
J 0
(-1790 2060);
DISPLAY 0.659574 (-1790 2060);
PAINT MONO (-1790 2060);
DISPLAY INVISIBLE (-1790 2060);
FORCEPROP 1 LASTPIN (-1800 2050) BN 7
J 2
(-1750 2060);
DISPLAY 0.617021 (-1750 2060);
PAINT PINK (-1750 2060);
FORCEPROP 2 LAST CDS_LIB mstr_standard
J 2
(-1750 2050);
DISPLAY 0.787234 (-1750 2050);
PAINT MONO (-1750 2050);
DISPLAY INVISIBLE (-1750 2050);
FORCEPROP 1 LAST BODY_TYPE PLUMBING
J 2
(-1750 2000);
DISPLAY 1.234043 (-1750 2000);
PAINT GREEN (-1750 2000);
DISPLAY INVISIBLE (-1750 2000);
FORCEPROP 1 LAST HDL_TAP TRUE
J 2
(-2075 1925);
DISPLAY 1.234043 (-2075 1925);
PAINT GREEN (-2075 1925);
DISPLAY INVISIBLE (-2075 1925);
FORCEPROP 1 LAST PATH I105
J 2
(-1750 2050);
DISPLAY 0.936170 (-1750 2050);
PAINT GREEN (-1750 2050);
DISPLAY INVISIBLE (-1750 2050);
FORCEADD TAP..6
R 2
(-1750 2150);
FORCEPROP 3 LASTPIN (-1800 2150) SIG_NAME M_L_DQ<9>
J 0
(-1790 2160);
DISPLAY 0.659574 (-1790 2160);
PAINT MONO (-1790 2160);
DISPLAY INVISIBLE (-1790 2160);
FORCEPROP 1 LASTPIN (-1800 2150) BN 9
J 2
(-1750 2160);
DISPLAY 0.617021 (-1750 2160);
PAINT PINK (-1750 2160);
FORCEPROP 2 LAST CDS_LIB mstr_standard
J 2
(-1750 2150);
DISPLAY 0.787234 (-1750 2150);
PAINT MONO (-1750 2150);
DISPLAY INVISIBLE (-1750 2150);
FORCEPROP 1 LAST BODY_TYPE PLUMBING
J 2
(-1750 2100);
DISPLAY 1.234043 (-1750 2100);
PAINT GREEN (-1750 2100);
DISPLAY INVISIBLE (-1750 2100);
FORCEPROP 1 LAST HDL_TAP TRUE
J 2
(-2075 2025);
DISPLAY 1.234043 (-2075 2025);
PAINT GREEN (-2075 2025);
DISPLAY INVISIBLE (-2075 2025);
FORCEPROP 1 LAST PATH I106
J 2
(-1750 2150);
DISPLAY 0.936170 (-1750 2150);
PAINT GREEN (-1750 2150);
DISPLAY INVISIBLE (-1750 2150);
FORCEADD TAP..6
R 2
(-1750 2100);
FORCEPROP 3 LASTPIN (-1800 2100) SIG_NAME M_L_DQ<6>
J 0
(-1790 2110);
DISPLAY 0.659574 (-1790 2110);
PAINT MONO (-1790 2110);
DISPLAY INVISIBLE (-1790 2110);
FORCEPROP 1 LASTPIN (-1800 2100) BN 6
J 2
(-1750 2110);
DISPLAY 0.617021 (-1750 2110);
PAINT PINK (-1750 2110);
FORCEPROP 2 LAST CDS_LIB mstr_standard
J 2
(-1750 2100);
DISPLAY 0.787234 (-1750 2100);
PAINT MONO (-1750 2100);
DISPLAY INVISIBLE (-1750 2100);
FORCEPROP 1 LAST BODY_TYPE PLUMBING
J 2
(-1750 2050);
DISPLAY 1.234043 (-1750 2050);
PAINT GREEN (-1750 2050);
DISPLAY INVISIBLE (-1750 2050);
FORCEPROP 1 LAST HDL_TAP TRUE
J 2
(-2075 1975);
DISPLAY 1.234043 (-2075 1975);
PAINT GREEN (-2075 1975);
DISPLAY INVISIBLE (-2075 1975);
FORCEPROP 1 LAST PATH I107
J 2
(-1750 2100);
DISPLAY 0.936170 (-1750 2100);
PAINT GREEN (-1750 2100);
DISPLAY INVISIBLE (-1750 2100);
FORCEADD TAP..6
R 2
(-1750 1750);
FORCEPROP 3 LASTPIN (-1800 1750) SIG_NAME M_L_DQ<1>
J 0
(-1790 1760);
DISPLAY 0.659574 (-1790 1760);
PAINT MONO (-1790 1760);
DISPLAY INVISIBLE (-1790 1760);
FORCEPROP 1 LASTPIN (-1800 1750) BN 1
J 2
(-1750 1760);
DISPLAY 0.617021 (-1750 1760);
PAINT PINK (-1750 1760);
FORCEPROP 2 LAST CDS_LIB mstr_standard
J 2
(-1750 1750);
DISPLAY 0.787234 (-1750 1750);
PAINT MONO (-1750 1750);
DISPLAY INVISIBLE (-1750 1750);
FORCEPROP 1 LAST BODY_TYPE PLUMBING
J 2
(-1750 1700);
DISPLAY 1.234043 (-1750 1700);
PAINT GREEN (-1750 1700);
DISPLAY INVISIBLE (-1750 1700);
FORCEPROP 1 LAST HDL_TAP TRUE
J 2
(-2075 1625);
DISPLAY 1.234043 (-2075 1625);
PAINT GREEN (-2075 1625);
DISPLAY INVISIBLE (-2075 1625);
FORCEPROP 1 LAST PATH I108
J 2
(-1750 1750);
DISPLAY 0.936170 (-1750 1750);
PAINT GREEN (-1750 1750);
DISPLAY INVISIBLE (-1750 1750);
FORCEADD TAP..6
R 2
(-1750 1850);
FORCEPROP 3 LASTPIN (-1800 1850) SIG_NAME M_L_DQ<3>
J 0
(-1790 1860);
DISPLAY 0.659574 (-1790 1860);
PAINT MONO (-1790 1860);
DISPLAY INVISIBLE (-1790 1860);
FORCEPROP 1 LASTPIN (-1800 1850) BN 3
J 2
(-1750 1860);
DISPLAY 0.617021 (-1750 1860);
PAINT PINK (-1750 1860);
FORCEPROP 2 LAST CDS_LIB mstr_standard
J 2
(-1750 1850);
DISPLAY 0.787234 (-1750 1850);
PAINT MONO (-1750 1850);
DISPLAY INVISIBLE (-1750 1850);
FORCEPROP 1 LAST BODY_TYPE PLUMBING
J 2
(-1750 1800);
DISPLAY 1.234043 (-1750 1800);
PAINT GREEN (-1750 1800);
DISPLAY INVISIBLE (-1750 1800);
FORCEPROP 1 LAST HDL_TAP TRUE
J 2
(-2075 1725);
DISPLAY 1.234043 (-2075 1725);
PAINT GREEN (-2075 1725);
DISPLAY INVISIBLE (-2075 1725);
FORCEPROP 1 LAST PATH I109
J 2
(-1750 1850);
DISPLAY 0.936170 (-1750 1850);
PAINT GREEN (-1750 1850);
DISPLAY INVISIBLE (-1750 1850);
FORCEADD TAP..6
R 2
(700 4950);
FORCEPROP 3 LASTPIN (650 4950) SIG_NAME M_L_DQS_DP<15>
J 0
(660 4960);
DISPLAY 0.659574 (660 4960);
PAINT MONO (660 4960);
DISPLAY INVISIBLE (660 4960);
FORCEPROP 1 LASTPIN (650 4950) BN 15
J 2
(700 4960);
DISPLAY 0.617021 (700 4960);
PAINT PINK (700 4960);
FORCEPROP 2 LAST CDS_LIB mstr_standard
J 0
(700 4950);
DISPLAY 0.787234 (700 4950);
PAINT MONO (700 4950);
DISPLAY INVISIBLE (700 4950);
FORCEPROP 1 LAST BODY_TYPE PLUMBING
J 2
(700 4900);
DISPLAY 1.234043 (700 4900);
PAINT GREEN (700 4900);
DISPLAY INVISIBLE (700 4900);
FORCEPROP 1 LAST HDL_TAP TRUE
J 2
(375 4825);
DISPLAY 1.234043 (375 4825);
PAINT GREEN (375 4825);
DISPLAY INVISIBLE (375 4825);
FORCEPROP 1 LAST PATH I11
J 2
(700 4950);
DISPLAY 0.936170 (700 4950);
PAINT GREEN (700 4950);
DISPLAY INVISIBLE (700 4950);
FORCEADD TAP..6
R 2
(-1750 1800);
FORCEPROP 3 LASTPIN (-1800 1800) SIG_NAME M_L_DQ<0>
J 0
(-1790 1810);
DISPLAY 0.659574 (-1790 1810);
PAINT MONO (-1790 1810);
DISPLAY INVISIBLE (-1790 1810);
FORCEPROP 1 LASTPIN (-1800 1800) BN 0
J 2
(-1750 1810);
DISPLAY 0.617021 (-1750 1810);
PAINT PINK (-1750 1810);
FORCEPROP 2 LAST CDS_LIB mstr_standard
J 2
(-1750 1800);
DISPLAY 0.787234 (-1750 1800);
PAINT MONO (-1750 1800);
DISPLAY INVISIBLE (-1750 1800);
FORCEPROP 1 LAST BODY_TYPE PLUMBING
J 2
(-1750 1750);
DISPLAY 1.234043 (-1750 1750);
PAINT GREEN (-1750 1750);
DISPLAY INVISIBLE (-1750 1750);
FORCEPROP 1 LAST HDL_TAP TRUE
J 2
(-2075 1675);
DISPLAY 1.234043 (-2075 1675);
PAINT GREEN (-2075 1675);
DISPLAY INVISIBLE (-2075 1675);
FORCEPROP 1 LAST PATH I110
J 2
(-1750 1800);
DISPLAY 0.936170 (-1750 1800);
PAINT GREEN (-1750 1800);
DISPLAY INVISIBLE (-1750 1800);
FORCEADD SCONN288_H44441004..1
(-2500 3250);
FORCEPROP 2 LASTPIN (-3000 4900) $PN 234
J 2
(-3010 4910);
DISPLAY 0.617021 (-3010 4910);
PAINT ORANGE (-3010 4910);
FORCEPROP 1 LAST LOCATION J1A2
J 0
(-2950 5150);
DISPLAY 0.617021 (-2950 5150);
PAINT AQUA (-2950 5150);
FORCEPROP 1 LAST PART_NUMBER H44441-004
J 0
(-2950 1250);
DISPLAY 0.617021 (-2950 1250);
PAINT BLUE (-2950 1250);
FORCEPROP 1 LAST MATERIAL SCONN
J 0
(-2950 5100);
DISPLAY 0.617021 (-2950 5100);
PAINT SKYBLUE (-2950 5100);
FORCEPROP 2 LASTPIN (-3000 1750) $PN 146
J 2
(-3010 1760);
DISPLAY 0.617021 (-3010 1760);
PAINT ORANGE (-3010 1760);
FORCEPROP 2 LASTPIN (-3000 2100) $PN 284
J 2
(-3010 2110);
DISPLAY 0.617021 (-3010 2110);
PAINT ORANGE (-3010 2110);
FORCEPROP 2 LASTPIN (-3000 1900) $PN 285
J 2
(-3010 1910);
DISPLAY 0.617021 (-3010 1910);
PAINT ORANGE (-3010 1910);
FORCEPROP 2 LASTPIN (-3000 1850) $PN 141
J 2
(-3010 1860);
DISPLAY 0.617021 (-3010 1860);
PAINT ORANGE (-3010 1860);
FORCEPROP 2 LASTPIN (-3000 1450) $PN 230
J 2
(-3010 1460);
DISPLAY 0.617021 (-3010 1460);
PAINT ORANGE (-3010 1460);
FORCEPROP 2 LASTPIN (-3000 2050) $PN 238
J 2
(-3010 2060);
DISPLAY 0.617021 (-3010 2060);
PAINT ORANGE (-3010 2060);
FORCEPROP 2 LASTPIN (-3000 2000) $PN 140
J 2
(-3010 2010);
DISPLAY 0.617021 (-3010 2010);
PAINT ORANGE (-3010 2010);
FORCEPROP 2 LASTPIN (-3000 1950) $PN 139
J 2
(-3010 1960);
DISPLAY 0.617021 (-3010 1960);
PAINT ORANGE (-3010 1960);
FORCEPROP 2 LASTPIN (-3000 3400) $PN 237
J 2
(-3010 3410);
DISPLAY 0.617021 (-3010 3410);
PAINT ORANGE (-3010 3410);
FORCEPROP 2 LASTPIN (-3000 3350) $PN 93
J 2
(-3010 3360);
DISPLAY 0.617021 (-3010 3360);
PAINT ORANGE (-3010 3360);
FORCEPROP 2 LASTPIN (-3000 3300) $PN 89
J 2
(-3010 3310);
DISPLAY 0.617021 (-3010 3310);
PAINT ORANGE (-3010 3310);
FORCEPROP 2 LASTPIN (-3000 3250) $PN 84
J 2
(-3010 3260);
DISPLAY 0.617021 (-3010 3260);
PAINT ORANGE (-3010 3260);
FORCEPROP 2 LASTPIN (-3000 1650) $PN 144
J 2
(-3010 1660);
DISPLAY 0.617021 (-3010 1660);
PAINT ORANGE (-3010 1660);
FORCEPROP 2 LASTPIN (-3000 1600) $PN 227
J 2
(-3010 1610);
DISPLAY 0.617021 (-3010 1610);
PAINT ORANGE (-3010 1610);
FORCEPROP 2 LASTPIN (-3000 1550) $PN 205
J 2
(-3010 1560);
DISPLAY 0.617021 (-3010 1560);
PAINT ORANGE (-3010 1560);
FORCEPROP 2 LASTPIN (-3000 2350) $PN 58
J 2
(-3010 2360);
DISPLAY 0.617021 (-3010 2360);
PAINT ORANGE (-3010 2360);
FORCEPROP 2 LASTPIN (-3000 2400) $PN 222
J 2
(-3010 2410);
DISPLAY 0.617021 (-3010 2410);
PAINT ORANGE (-3010 2410);
FORCEPROP 2 LASTPIN (-3000 3000) $PN 91
J 2
(-3010 3010);
DISPLAY 0.617021 (-3010 3010);
PAINT ORANGE (-3010 3010);
FORCEPROP 2 LASTPIN (-3000 2950) $PN 87
J 2
(-3010 2960);
DISPLAY 0.617021 (-3010 2960);
PAINT ORANGE (-3010 2960);
FORCEPROP 2 LASTPIN (-3000 2300) $PN 78
J 2
(-3010 2310);
DISPLAY 0.617021 (-3010 2310);
PAINT ORANGE (-3010 2310);
FORCEPROP 2 LASTPIN (-2000 4900) $PN 280
J 0
(-1990 4910);
DISPLAY 0.617021 (-1990 4910);
PAINT ORANGE (-1990 4910);
FORCEPROP 2 LASTPIN (-2000 4850) $PN 135
J 0
(-1990 4860);
DISPLAY 0.617021 (-1990 4860);
PAINT ORANGE (-1990 4860);
FORCEPROP 2 LASTPIN (-2000 4800) $PN 273
J 0
(-1990 4810);
DISPLAY 0.617021 (-1990 4810);
PAINT ORANGE (-1990 4810);
FORCEPROP 2 LASTPIN (-2000 4750) $PN 128
J 0
(-1990 4760);
DISPLAY 0.617021 (-1990 4760);
PAINT ORANGE (-1990 4760);
FORCEPROP 2 LASTPIN (-2000 4650) $PN 137
J 0
(-1990 4660);
DISPLAY 0.617021 (-1990 4660);
PAINT ORANGE (-1990 4660);
FORCEPROP 2 LASTPIN (-2000 4600) $PN 275
J 0
(-1990 4610);
DISPLAY 0.617021 (-1990 4610);
PAINT ORANGE (-1990 4610);
FORCEPROP 2 LASTPIN (-2000 4550) $PN 130
J 0
(-1990 4560);
DISPLAY 0.617021 (-1990 4560);
PAINT ORANGE (-1990 4560);
FORCEPROP 2 LASTPIN (-2000 4500) $PN 269
J 0
(-1990 4510);
DISPLAY 0.617021 (-1990 4510);
PAINT ORANGE (-1990 4510);
FORCEPROP 2 LASTPIN (-2000 4450) $PN 124
J 0
(-1990 4460);
DISPLAY 0.617021 (-1990 4460);
PAINT ORANGE (-1990 4460);
FORCEPROP 2 LASTPIN (-2000 4400) $PN 262
J 0
(-1990 4410);
DISPLAY 0.617021 (-1990 4410);
PAINT ORANGE (-1990 4410);
FORCEPROP 2 LASTPIN (-2000 4350) $PN 117
J 0
(-1990 4360);
DISPLAY 0.617021 (-1990 4360);
PAINT ORANGE (-1990 4360);
FORCEPROP 2 LASTPIN (-2000 4300) $PN 271
J 0
(-1990 4310);
DISPLAY 0.617021 (-1990 4310);
PAINT ORANGE (-1990 4310);
FORCEPROP 2 LASTPIN (-2000 4250) $PN 126
J 0
(-1990 4260);
DISPLAY 0.617021 (-1990 4260);
PAINT ORANGE (-1990 4260);
FORCEPROP 2 LASTPIN (-2000 4200) $PN 264
J 0
(-1990 4210);
DISPLAY 0.617021 (-1990 4210);
PAINT ORANGE (-1990 4210);
FORCEPROP 2 LASTPIN (-2000 4150) $PN 119
J 0
(-1990 4160);
DISPLAY 0.617021 (-1990 4160);
PAINT ORANGE (-1990 4160);
FORCEPROP 2 LASTPIN (-2000 4100) $PN 258
J 0
(-1990 4110);
DISPLAY 0.617021 (-1990 4110);
PAINT ORANGE (-1990 4110);
FORCEPROP 2 LASTPIN (-2000 4050) $PN 113
J 0
(-1990 4060);
DISPLAY 0.617021 (-1990 4060);
PAINT ORANGE (-1990 4060);
FORCEPROP 2 LASTPIN (-2000 4000) $PN 251
J 0
(-1990 4010);
DISPLAY 0.617021 (-1990 4010);
PAINT ORANGE (-1990 4010);
FORCEPROP 2 LASTPIN (-2000 3950) $PN 106
J 0
(-1990 3960);
DISPLAY 0.617021 (-1990 3960);
PAINT ORANGE (-1990 3960);
FORCEPROP 2 LASTPIN (-2000 3900) $PN 260
J 0
(-1990 3910);
DISPLAY 0.617021 (-1990 3910);
PAINT ORANGE (-1990 3910);
FORCEPROP 2 LASTPIN (-2000 3850) $PN 115
J 0
(-1990 3860);
DISPLAY 0.617021 (-1990 3860);
PAINT ORANGE (-1990 3860);
FORCEPROP 2 LASTPIN (-2000 3800) $PN 253
J 0
(-1990 3810);
DISPLAY 0.617021 (-1990 3810);
PAINT ORANGE (-1990 3810);
FORCEPROP 2 LASTPIN (-2000 3750) $PN 108
J 0
(-1990 3760);
DISPLAY 0.617021 (-1990 3760);
PAINT ORANGE (-1990 3760);
FORCEPROP 2 LASTPIN (-2000 3700) $PN 247
J 0
(-1990 3710);
DISPLAY 0.617021 (-1990 3710);
PAINT ORANGE (-1990 3710);
FORCEPROP 2 LASTPIN (-2000 3650) $PN 102
J 0
(-1990 3660);
DISPLAY 0.617021 (-1990 3660);
PAINT ORANGE (-1990 3660);
FORCEPROP 2 LASTPIN (-2000 3550) $PN 95
J 0
(-1990 3560);
DISPLAY 0.617021 (-1990 3560);
PAINT ORANGE (-1990 3560);
FORCEPROP 2 LASTPIN (-2000 3500) $PN 249
J 0
(-1990 3510);
DISPLAY 0.617021 (-1990 3510);
PAINT ORANGE (-1990 3510);
FORCEPROP 2 LASTPIN (-2000 3450) $PN 104
J 0
(-1990 3460);
DISPLAY 0.617021 (-1990 3460);
PAINT ORANGE (-1990 3460);
FORCEPROP 2 LASTPIN (-2000 3350) $PN 97
J 0
(-1990 3360);
DISPLAY 0.617021 (-1990 3360);
PAINT ORANGE (-1990 3360);
FORCEPROP 2 LASTPIN (-2000 3300) $PN 188
J 0
(-1990 3310);
DISPLAY 0.617021 (-1990 3310);
PAINT ORANGE (-1990 3310);
FORCEPROP 2 LASTPIN (-2000 3250) $PN 43
J 0
(-1990 3260);
DISPLAY 0.617021 (-1990 3260);
PAINT ORANGE (-1990 3260);
FORCEPROP 2 LASTPIN (-2000 3200) $PN 181
J 0
(-1990 3210);
DISPLAY 0.617021 (-1990 3210);
PAINT ORANGE (-1990 3210);
FORCEPROP 2 LASTPIN (-2000 3150) $PN 36
J 0
(-1990 3160);
DISPLAY 0.617021 (-1990 3160);
PAINT ORANGE (-1990 3160);
FORCEPROP 2 LASTPIN (-2000 3100) $PN 190
J 0
(-1990 3110);
DISPLAY 0.617021 (-1990 3110);
PAINT ORANGE (-1990 3110);
FORCEPROP 2 LASTPIN (-2000 3050) $PN 45
J 0
(-1990 3060);
DISPLAY 0.617021 (-1990 3060);
PAINT ORANGE (-1990 3060);
FORCEPROP 2 LASTPIN (-2000 3000) $PN 183
J 0
(-1990 3010);
DISPLAY 0.617021 (-1990 3010);
PAINT ORANGE (-1990 3010);
FORCEPROP 2 LASTPIN (-2000 2950) $PN 38
J 0
(-1990 2960);
DISPLAY 0.617021 (-1990 2960);
PAINT ORANGE (-1990 2960);
FORCEPROP 2 LASTPIN (-2000 2900) $PN 177
J 0
(-1990 2910);
DISPLAY 0.617021 (-1990 2910);
PAINT ORANGE (-1990 2910);
FORCEPROP 2 LASTPIN (-2000 2850) $PN 32
J 0
(-1990 2860);
DISPLAY 0.617021 (-1990 2860);
PAINT ORANGE (-1990 2860);
FORCEPROP 2 LASTPIN (-2000 2800) $PN 170
J 0
(-1990 2810);
DISPLAY 0.617021 (-1990 2810);
PAINT ORANGE (-1990 2810);
FORCEPROP 2 LASTPIN (-2000 2750) $PN 25
J 0
(-1990 2760);
DISPLAY 0.617021 (-1990 2760);
PAINT ORANGE (-1990 2760);
FORCEPROP 2 LASTPIN (-2000 2700) $PN 179
J 0
(-1990 2710);
DISPLAY 0.617021 (-1990 2710);
PAINT ORANGE (-1990 2710);
FORCEPROP 2 LASTPIN (-2000 2650) $PN 34
J 0
(-1990 2660);
DISPLAY 0.617021 (-1990 2660);
PAINT ORANGE (-1990 2660);
FORCEPROP 2 LASTPIN (-2000 2600) $PN 172
J 0
(-1990 2610);
DISPLAY 0.617021 (-1990 2610);
PAINT ORANGE (-1990 2610);
FORCEPROP 2 LASTPIN (-2000 2550) $PN 27
J 0
(-1990 2560);
DISPLAY 0.617021 (-1990 2560);
PAINT ORANGE (-1990 2560);
FORCEPROP 2 LASTPIN (-2000 2500) $PN 166
J 0
(-1990 2510);
DISPLAY 0.617021 (-1990 2510);
PAINT ORANGE (-1990 2510);
FORCEPROP 2 LASTPIN (-2000 2450) $PN 21
J 0
(-1990 2460);
DISPLAY 0.617021 (-1990 2460);
PAINT ORANGE (-1990 2460);
FORCEPROP 2 LASTPIN (-2000 2400) $PN 159
J 0
(-1990 2410);
DISPLAY 0.617021 (-1990 2410);
PAINT ORANGE (-1990 2410);
FORCEPROP 2 LASTPIN (-2000 2350) $PN 14
J 0
(-1990 2360);
DISPLAY 0.617021 (-1990 2360);
PAINT ORANGE (-1990 2360);
FORCEPROP 2 LASTPIN (-2000 2300) $PN 168
J 0
(-1990 2310);
DISPLAY 0.617021 (-1990 2310);
PAINT ORANGE (-1990 2310);
FORCEPROP 2 LASTPIN (-2000 2250) $PN 23
J 0
(-1990 2260);
DISPLAY 0.617021 (-1990 2260);
PAINT ORANGE (-1990 2260);
FORCEPROP 2 LASTPIN (-2000 2200) $PN 161
J 0
(-1990 2210);
DISPLAY 0.617021 (-1990 2210);
PAINT ORANGE (-1990 2210);
FORCEPROP 2 LASTPIN (-2000 2150) $PN 16
J 0
(-1990 2160);
DISPLAY 0.617021 (-1990 2160);
PAINT ORANGE (-1990 2160);
FORCEPROP 2 LASTPIN (-2000 2100) $PN 155
J 0
(-1990 2110);
DISPLAY 0.617021 (-1990 2110);
PAINT ORANGE (-1990 2110);
FORCEPROP 2 LASTPIN (-2000 2050) $PN 10
J 0
(-1990 2060);
DISPLAY 0.617021 (-1990 2060);
PAINT ORANGE (-1990 2060);
FORCEPROP 2 LASTPIN (-2000 2000) $PN 148
J 0
(-1990 2010);
DISPLAY 0.617021 (-1990 2010);
PAINT ORANGE (-1990 2010);
FORCEPROP 2 LASTPIN (-2000 1950) $PN 3
J 0
(-1990 1960);
DISPLAY 0.617021 (-1990 1960);
PAINT ORANGE (-1990 1960);
FORCEPROP 2 LASTPIN (-2000 1900) $PN 157
J 0
(-1990 1910);
DISPLAY 0.617021 (-1990 1910);
PAINT ORANGE (-1990 1910);
FORCEPROP 2 LASTPIN (-2000 1850) $PN 12
J 0
(-1990 1860);
DISPLAY 0.617021 (-1990 1860);
PAINT ORANGE (-1990 1860);
FORCEPROP 2 LASTPIN (-2000 1800) $PN 150
J 0
(-1990 1810);
DISPLAY 0.617021 (-1990 1810);
PAINT ORANGE (-1990 1810);
FORCEPROP 2 LASTPIN (-2000 1750) $PN 5
J 0
(-1990 1760);
DISPLAY 0.617021 (-1990 1760);
PAINT ORANGE (-1990 1760);
FORCEPROP 2 LASTPIN (-3000 3150) $PN 203
J 2
(-3010 3160);
DISPLAY 0.617021 (-3010 3160);
PAINT ORANGE (-3010 3160);
FORCEPROP 2 LASTPIN (-3000 3100) $PN 60
J 2
(-3010 3110);
DISPLAY 0.617021 (-3010 3110);
PAINT ORANGE (-3010 3110);
FORCEPROP 2 LASTPIN (-3000 3700) $PN 218
J 2
(-3010 3710);
DISPLAY 0.617021 (-3010 3710);
PAINT ORANGE (-3010 3710);
FORCEPROP 2 LASTPIN (-3000 3650) $PN 219
J 2
(-3010 3660);
DISPLAY 0.617021 (-3010 3660);
PAINT ORANGE (-3010 3660);
FORCEPROP 2 LASTPIN (-3000 3600) $PN 74
J 2
(-3010 3610);
DISPLAY 0.617021 (-3010 3610);
PAINT ORANGE (-3010 3610);
FORCEPROP 2 LASTPIN (-3000 3550) $PN 75
J 2
(-3010 3560);
DISPLAY 0.617021 (-3010 3560);
PAINT ORANGE (-3010 3560);
FORCEPROP 2 LASTPIN (-3000 2850) $PN 199
J 2
(-3010 2860);
DISPLAY 0.617021 (-3010 2860);
PAINT ORANGE (-3010 2860);
FORCEPROP 2 LASTPIN (-3000 2800) $PN 54
J 2
(-3010 2810);
DISPLAY 0.617021 (-3010 2810);
PAINT ORANGE (-3010 2810);
FORCEPROP 2 LASTPIN (-3000 2750) $PN 192
J 2
(-3010 2760);
DISPLAY 0.617021 (-3010 2760);
PAINT ORANGE (-3010 2760);
FORCEPROP 2 LASTPIN (-3000 2700) $PN 47
J 2
(-3010 2710);
DISPLAY 0.617021 (-3010 2710);
PAINT ORANGE (-3010 2710);
FORCEPROP 2 LASTPIN (-3000 2650) $PN 201
J 2
(-3010 2660);
DISPLAY 0.617021 (-3010 2660);
PAINT ORANGE (-3010 2660);
FORCEPROP 2 LASTPIN (-3000 2600) $PN 56
J 2
(-3010 2610);
DISPLAY 0.617021 (-3010 2610);
PAINT ORANGE (-3010 2610);
FORCEPROP 2 LASTPIN (-3000 2550) $PN 194
J 2
(-3010 2560);
DISPLAY 0.617021 (-3010 2560);
PAINT ORANGE (-3010 2560);
FORCEPROP 2 LASTPIN (-3000 2500) $PN 49
J 2
(-3010 2510);
DISPLAY 0.617021 (-3010 2510);
PAINT ORANGE (-3010 2510);
FORCEPROP 2 LASTPIN (-3000 3450) $PN 235
J 2
(-3010 3460);
DISPLAY 0.617021 (-3010 3460);
PAINT ORANGE (-3010 3460);
FORCEPROP 2 LASTPIN (-3000 3850) $PN 207
J 2
(-3010 3860);
DISPLAY 0.617021 (-3010 3860);
PAINT ORANGE (-3010 3860);
FORCEPROP 2 LASTPIN (-3000 3800) $PN 63
J 2
(-3010 3810);
DISPLAY 0.617021 (-3010 3810);
PAINT ORANGE (-3010 3810);
FORCEPROP 2 LASTPIN (-3000 3950) $PN 224
J 2
(-3010 3960);
DISPLAY 0.617021 (-3010 3960);
PAINT ORANGE (-3010 3960);
FORCEPROP 2 LASTPIN (-3000 3900) $PN 81
J 2
(-3010 3910);
DISPLAY 0.617021 (-3010 3910);
PAINT ORANGE (-3010 3910);
FORCEPROP 2 LASTPIN (-3000 2250) $PN 208
J 2
(-3010 2260);
DISPLAY 0.617021 (-3010 2260);
PAINT ORANGE (-3010 2260);
FORCEPROP 2 LASTPIN (-3000 2200) $PN 62
J 2
(-3010 2210);
DISPLAY 0.617021 (-3010 2210);
PAINT ORANGE (-3010 2210);
FORCEPROP 2 LASTPIN (-3000 4850) $PN 82
J 2
(-3010 4860);
DISPLAY 0.617021 (-3010 4860);
PAINT ORANGE (-3010 4860);
FORCEPROP 2 LASTPIN (-3000 4800) $PN 86
J 2
(-3010 4810);
DISPLAY 0.617021 (-3010 4810);
PAINT ORANGE (-3010 4810);
FORCEPROP 2 LASTPIN (-3000 4750) $PN 228
J 2
(-3010 4760);
DISPLAY 0.617021 (-3010 4760);
PAINT ORANGE (-3010 4760);
FORCEPROP 2 LASTPIN (-3000 4700) $PN 232
J 2
(-3010 4710);
DISPLAY 0.617021 (-3010 4710);
PAINT ORANGE (-3010 4710);
FORCEPROP 2 LASTPIN (-3000 4650) $PN 65
J 2
(-3010 4660);
DISPLAY 0.617021 (-3010 4660);
PAINT ORANGE (-3010 4660);
FORCEPROP 2 LASTPIN (-3000 4600) $PN 210
J 2
(-3010 4610);
DISPLAY 0.617021 (-3010 4610);
PAINT ORANGE (-3010 4610);
FORCEPROP 2 LASTPIN (-3000 4550) $PN 225
J 2
(-3010 4560);
DISPLAY 0.617021 (-3010 4560);
PAINT ORANGE (-3010 4560);
FORCEPROP 2 LASTPIN (-3000 4500) $PN 66
J 2
(-3010 4510);
DISPLAY 0.617021 (-3010 4510);
PAINT ORANGE (-3010 4510);
FORCEPROP 2 LASTPIN (-3000 4450) $PN 68
J 2
(-3010 4460);
DISPLAY 0.617021 (-3010 4460);
PAINT ORANGE (-3010 4460);
FORCEPROP 2 LASTPIN (-3000 4400) $PN 211
J 2
(-3010 4410);
DISPLAY 0.617021 (-3010 4410);
PAINT ORANGE (-3010 4410);
FORCEPROP 2 LASTPIN (-3000 4350) $PN 69
J 2
(-3010 4360);
DISPLAY 0.617021 (-3010 4360);
PAINT ORANGE (-3010 4360);
FORCEPROP 2 LASTPIN (-3000 4300) $PN 213
J 2
(-3010 4310);
DISPLAY 0.617021 (-3010 4310);
PAINT ORANGE (-3010 4310);
FORCEPROP 2 LASTPIN (-3000 4250) $PN 214
J 2
(-3010 4260);
DISPLAY 0.617021 (-3010 4260);
PAINT ORANGE (-3010 4260);
FORCEPROP 2 LASTPIN (-3000 4200) $PN 71
J 2
(-3010 4210);
DISPLAY 0.617021 (-3010 4210);
PAINT ORANGE (-3010 4210);
FORCEPROP 2 LASTPIN (-3000 4150) $PN 216
J 2
(-3010 4160);
DISPLAY 0.617021 (-3010 4160);
PAINT ORANGE (-3010 4160);
FORCEPROP 2 LASTPIN (-3000 4100) $PN 72
J 2
(-3010 4110);
DISPLAY 0.617021 (-3010 4110);
PAINT ORANGE (-3010 4110);
FORCEPROP 2 LASTPIN (-3000 4050) $PN 79
J 2
(-3010 4060);
DISPLAY 0.617021 (-3010 4060);
PAINT ORANGE (-3010 4060);
FORCEPROP 2 LASTPIN (-2000 3600) $PN 240
J 0
(-1990 3610);
DISPLAY 0.617021 (-1990 3610);
PAINT ORANGE (-1990 3610);
FORCEPROP 2 LASTPIN (-2000 4700) $PN 282
J 0
(-1990 4710);
DISPLAY 0.617021 (-1990 4710);
PAINT ORANGE (-1990 4710);
FORCEPROP 2 LASTPIN (-2000 3400) $PN 242
J 0
(-1990 3410);
DISPLAY 0.617021 (-1990 3410);
PAINT ORANGE (-1990 3410);
FORCEPROP 1 LAST PACK_TYPE PIP
J 0
(-2950 5200);
PAINT SKYBLUE (-2950 5200);
DISPLAY INVISIBLE (-2950 5200);
FORCEPROP 2 LAST BOM_COST MEM
J 0
(-2500 3250);
PAINT ORANGE (-2500 3250);
DISPLAY INVISIBLE (-2500 3250);
FORCEPROP 2 LAST CDS_LIB mstr_sconn
J 0
(-2500 3250);
PAINT ORANGE (-2500 3250);
DISPLAY INVISIBLE (-2500 3250);
FORCEPROP 2 LAST SEC_TYPE PIP
J 0
(-2950 5200);
DISPLAY 1.021277 (-2950 5200);
PAINT ORANGE (-2950 5200);
DISPLAY INVISIBLE (-2950 5200);
FORCEPROP 2 LAST SEC 1
J 0
(-2950 5200);
DISPLAY 0.680851 (-2950 5200);
PAINT MONO (-2950 5200);
DISPLAY INVISIBLE (-2950 5200);
FORCEPROP 2 LAST CDS_LOCATION J1A2
J 0
(-2950 5150);
DISPLAY 0.617021 (-2950 5150);
PAINT AQUA (-2950 5150);
DISPLAY INVISIBLE (-2950 5150);
FORCEPROP 1 LAST PATH I111
J 0
(-2500 5100);
PAINT GREEN (-2500 5100);
DISPLAY INVISIBLE (-2500 5100);
FORCEPROP 2 LAST ROOM DDR4_CH_L
J 0
(-2500 3250);
PAINT ORANGE (-2500 3250);
DISPLAY INVISIBLE (-2500 3250);
FORCEADD TAP..6
(-3250 4850);
FORCEPROP 3 LASTPIN (-3200 4850) SIG_NAME M_L_MA<16>
J 0
(-3190 4860);
DISPLAY 0.659574 (-3190 4860);
PAINT MONO (-3190 4860);
DISPLAY INVISIBLE (-3190 4860);
FORCEPROP 1 LASTPIN (-3200 4850) BN 16
J 0
(-3250 4860);
DISPLAY 0.617021 (-3250 4860);
PAINT PINK (-3250 4860);
FORCEPROP 2 LAST CDS_LIB mstr_standard
J 2
(-3250 4850);
DISPLAY 0.787234 (-3250 4850);
PAINT MONO (-3250 4850);
DISPLAY INVISIBLE (-3250 4850);
FORCEPROP 1 LAST BODY_TYPE PLUMBING
J 0
(-3250 4800);
DISPLAY 1.234043 (-3250 4800);
PAINT GREEN (-3250 4800);
DISPLAY INVISIBLE (-3250 4800);
FORCEPROP 1 LAST HDL_TAP TRUE
J 0
(-2925 4725);
DISPLAY 1.234043 (-2925 4725);
PAINT GREEN (-2925 4725);
DISPLAY INVISIBLE (-2925 4725);
FORCEPROP 1 LAST PATH I112
J 0
(-3250 4850);
DISPLAY 0.936170 (-3250 4850);
PAINT GREEN (-3250 4850);
DISPLAY INVISIBLE (-3250 4850);
FORCEADD TAP..6
(-3250 4900);
FORCEPROP 3 LASTPIN (-3200 4900) SIG_NAME M_L_MA<17>
J 0
(-3190 4910);
DISPLAY 0.659574 (-3190 4910);
PAINT MONO (-3190 4910);
DISPLAY INVISIBLE (-3190 4910);
FORCEPROP 1 LASTPIN (-3200 4900) BN 17
J 0
(-3250 4910);
DISPLAY 0.617021 (-3250 4910);
PAINT PINK (-3250 4910);
FORCEPROP 2 LAST CDS_LIB mstr_standard
J 0
(-3250 4900);
DISPLAY 0.787234 (-3250 4900);
PAINT MONO (-3250 4900);
DISPLAY INVISIBLE (-3250 4900);
FORCEPROP 1 LAST BODY_TYPE PLUMBING
J 0
(-3250 4850);
DISPLAY 1.234043 (-3250 4850);
PAINT GREEN (-3250 4850);
DISPLAY INVISIBLE (-3250 4850);
FORCEPROP 1 LAST HDL_TAP TRUE
J 0
(-2925 4775);
DISPLAY 1.234043 (-2925 4775);
PAINT GREEN (-2925 4775);
DISPLAY INVISIBLE (-2925 4775);
FORCEPROP 1 LAST PATH I113
J 0
(-3250 4900);
DISPLAY 0.936170 (-3250 4900);
PAINT GREEN (-3250 4900);
DISPLAY INVISIBLE (-3250 4900);
FORCEADD TAP..6
(-3250 4800);
FORCEPROP 3 LASTPIN (-3200 4800) SIG_NAME M_L_MA<15>
J 0
(-3190 4810);
DISPLAY 0.659574 (-3190 4810);
PAINT MONO (-3190 4810);
DISPLAY INVISIBLE (-3190 4810);
FORCEPROP 1 LASTPIN (-3200 4800) BN 15
J 0
(-3250 4810);
DISPLAY 0.617021 (-3250 4810);
PAINT PINK (-3250 4810);
FORCEPROP 2 LAST CDS_LIB mstr_standard
J 2
(-3250 4800);
DISPLAY 0.787234 (-3250 4800);
PAINT MONO (-3250 4800);
DISPLAY INVISIBLE (-3250 4800);
FORCEPROP 1 LAST BODY_TYPE PLUMBING
J 0
(-3250 4750);
DISPLAY 1.234043 (-3250 4750);
PAINT GREEN (-3250 4750);
DISPLAY INVISIBLE (-3250 4750);
FORCEPROP 1 LAST HDL_TAP TRUE
J 0
(-2925 4675);
DISPLAY 1.234043 (-2925 4675);
PAINT GREEN (-2925 4675);
DISPLAY INVISIBLE (-2925 4675);
FORCEPROP 1 LAST PATH I114
J 0
(-3250 4800);
DISPLAY 0.936170 (-3250 4800);
PAINT GREEN (-3250 4800);
DISPLAY INVISIBLE (-3250 4800);
FORCEADD TAP..6
(-3250 4750);
FORCEPROP 3 LASTPIN (-3200 4750) SIG_NAME M_L_MA<14>
J 0
(-3190 4760);
DISPLAY 0.659574 (-3190 4760);
PAINT MONO (-3190 4760);
DISPLAY INVISIBLE (-3190 4760);
FORCEPROP 1 LASTPIN (-3200 4750) BN 14
J 0
(-3250 4760);
DISPLAY 0.617021 (-3250 4760);
PAINT PINK (-3250 4760);
FORCEPROP 2 LAST CDS_LIB mstr_standard
J 2
(-3250 4750);
DISPLAY 0.787234 (-3250 4750);
PAINT MONO (-3250 4750);
DISPLAY INVISIBLE (-3250 4750);
FORCEPROP 1 LAST BODY_TYPE PLUMBING
J 0
(-3250 4700);
DISPLAY 1.234043 (-3250 4700);
PAINT GREEN (-3250 4700);
DISPLAY INVISIBLE (-3250 4700);
FORCEPROP 1 LAST HDL_TAP TRUE
J 0
(-2925 4625);
DISPLAY 1.234043 (-2925 4625);
PAINT GREEN (-2925 4625);
DISPLAY INVISIBLE (-2925 4625);
FORCEPROP 1 LAST PATH I115
J 0
(-3250 4750);
DISPLAY 0.936170 (-3250 4750);
PAINT GREEN (-3250 4750);
DISPLAY INVISIBLE (-3250 4750);
FORCEADD TAP..6
(-3250 4700);
FORCEPROP 3 LASTPIN (-3200 4700) SIG_NAME M_L_MA<13>
J 0
(-3190 4710);
DISPLAY 0.659574 (-3190 4710);
PAINT MONO (-3190 4710);
DISPLAY INVISIBLE (-3190 4710);
FORCEPROP 1 LASTPIN (-3200 4700) BN 13
J 0
(-3250 4710);
DISPLAY 0.617021 (-3250 4710);
PAINT PINK (-3250 4710);
FORCEPROP 2 LAST CDS_LIB mstr_standard
J 2
(-3250 4700);
DISPLAY 0.787234 (-3250 4700);
PAINT MONO (-3250 4700);
DISPLAY INVISIBLE (-3250 4700);
FORCEPROP 1 LAST BODY_TYPE PLUMBING
J 0
(-3250 4650);
DISPLAY 1.234043 (-3250 4650);
PAINT GREEN (-3250 4650);
DISPLAY INVISIBLE (-3250 4650);
FORCEPROP 1 LAST HDL_TAP TRUE
J 0
(-2925 4575);
DISPLAY 1.234043 (-2925 4575);
PAINT GREEN (-2925 4575);
DISPLAY INVISIBLE (-2925 4575);
FORCEPROP 1 LAST PATH I116
J 0
(-3250 4700);
DISPLAY 0.936170 (-3250 4700);
PAINT GREEN (-3250 4700);
DISPLAY INVISIBLE (-3250 4700);
FORCEADD TAP..6
(-3250 4650);
FORCEPROP 3 LASTPIN (-3200 4650) SIG_NAME M_L_MA<12>
J 0
(-3190 4660);
DISPLAY 0.659574 (-3190 4660);
PAINT MONO (-3190 4660);
DISPLAY INVISIBLE (-3190 4660);
FORCEPROP 1 LASTPIN (-3200 4650) BN 12
J 0
(-3250 4660);
DISPLAY 0.617021 (-3250 4660);
PAINT PINK (-3250 4660);
FORCEPROP 2 LAST CDS_LIB mstr_standard
J 2
(-3250 4650);
DISPLAY 0.787234 (-3250 4650);
PAINT MONO (-3250 4650);
DISPLAY INVISIBLE (-3250 4650);
FORCEPROP 1 LAST BODY_TYPE PLUMBING
J 0
(-3250 4600);
DISPLAY 1.234043 (-3250 4600);
PAINT GREEN (-3250 4600);
DISPLAY INVISIBLE (-3250 4600);
FORCEPROP 1 LAST HDL_TAP TRUE
J 0
(-2925 4525);
DISPLAY 1.234043 (-2925 4525);
PAINT GREEN (-2925 4525);
DISPLAY INVISIBLE (-2925 4525);
FORCEPROP 1 LAST PATH I117
J 0
(-3250 4650);
DISPLAY 0.936170 (-3250 4650);
PAINT GREEN (-3250 4650);
DISPLAY INVISIBLE (-3250 4650);
FORCEADD TAP..6
(-3250 4600);
FORCEPROP 3 LASTPIN (-3200 4600) SIG_NAME M_L_MA<11>
J 0
(-3190 4610);
DISPLAY 0.659574 (-3190 4610);
PAINT MONO (-3190 4610);
DISPLAY INVISIBLE (-3190 4610);
FORCEPROP 1 LASTPIN (-3200 4600) BN 11
J 0
(-3250 4610);
DISPLAY 0.617021 (-3250 4610);
PAINT PINK (-3250 4610);
FORCEPROP 2 LAST CDS_LIB mstr_standard
J 2
(-3250 4600);
DISPLAY 0.787234 (-3250 4600);
PAINT MONO (-3250 4600);
DISPLAY INVISIBLE (-3250 4600);
FORCEPROP 1 LAST BODY_TYPE PLUMBING
J 0
(-3250 4550);
DISPLAY 1.234043 (-3250 4550);
PAINT GREEN (-3250 4550);
DISPLAY INVISIBLE (-3250 4550);
FORCEPROP 1 LAST HDL_TAP TRUE
J 0
(-2925 4475);
DISPLAY 1.234043 (-2925 4475);
PAINT GREEN (-2925 4475);
DISPLAY INVISIBLE (-2925 4475);
FORCEPROP 1 LAST PATH I118
J 0
(-3250 4600);
DISPLAY 0.936170 (-3250 4600);
PAINT GREEN (-3250 4600);
DISPLAY INVISIBLE (-3250 4600);
FORCEADD TAP..6
(-3250 4550);
FORCEPROP 3 LASTPIN (-3200 4550) SIG_NAME M_L_MA<10>
J 0
(-3190 4560);
DISPLAY 0.659574 (-3190 4560);
PAINT MONO (-3190 4560);
DISPLAY INVISIBLE (-3190 4560);
FORCEPROP 1 LASTPIN (-3200 4550) BN 10
J 0
(-3250 4560);
DISPLAY 0.617021 (-3250 4560);
PAINT PINK (-3250 4560);
FORCEPROP 2 LAST CDS_LIB mstr_standard
J 2
(-3250 4550);
DISPLAY 0.787234 (-3250 4550);
PAINT MONO (-3250 4550);
DISPLAY INVISIBLE (-3250 4550);
FORCEPROP 1 LAST BODY_TYPE PLUMBING
J 0
(-3250 4500);
DISPLAY 1.234043 (-3250 4500);
PAINT GREEN (-3250 4500);
DISPLAY INVISIBLE (-3250 4500);
FORCEPROP 1 LAST HDL_TAP TRUE
J 0
(-2925 4425);
DISPLAY 1.234043 (-2925 4425);
PAINT GREEN (-2925 4425);
DISPLAY INVISIBLE (-2925 4425);
FORCEPROP 1 LAST PATH I119
J 0
(-3250 4550);
DISPLAY 0.936170 (-3250 4550);
PAINT GREEN (-3250 4550);
DISPLAY INVISIBLE (-3250 4550);
FORCEADD TAP..6
R 2
(700 5050);
FORCEPROP 3 LASTPIN (650 5050) SIG_NAME M_L_DQS_DP<16>
J 0
(660 5060);
DISPLAY 0.659574 (660 5060);
PAINT MONO (660 5060);
DISPLAY INVISIBLE (660 5060);
FORCEPROP 1 LASTPIN (650 5050) BN 16
J 2
(700 5060);
DISPLAY 0.617021 (700 5060);
PAINT PINK (700 5060);
FORCEPROP 2 LAST CDS_LIB mstr_standard
J 0
(700 5050);
DISPLAY 0.787234 (700 5050);
PAINT MONO (700 5050);
DISPLAY INVISIBLE (700 5050);
FORCEPROP 1 LAST BODY_TYPE PLUMBING
J 2
(700 5000);
DISPLAY 1.234043 (700 5000);
PAINT GREEN (700 5000);
DISPLAY INVISIBLE (700 5000);
FORCEPROP 1 LAST HDL_TAP TRUE
J 2
(375 4925);
DISPLAY 1.234043 (375 4925);
PAINT GREEN (375 4925);
DISPLAY INVISIBLE (375 4925);
FORCEPROP 1 LAST PATH I12
J 2
(700 5050);
DISPLAY 0.936170 (700 5050);
PAINT GREEN (700 5050);
DISPLAY INVISIBLE (700 5050);
FORCEADD TAP..6
(-3250 4500);
FORCEPROP 3 LASTPIN (-3200 4500) SIG_NAME M_L_MA<9>
J 0
(-3190 4510);
DISPLAY 0.659574 (-3190 4510);
PAINT MONO (-3190 4510);
DISPLAY INVISIBLE (-3190 4510);
FORCEPROP 1 LASTPIN (-3200 4500) BN 9
J 0
(-3250 4510);
DISPLAY 0.617021 (-3250 4510);
PAINT PINK (-3250 4510);
FORCEPROP 2 LAST CDS_LIB mstr_standard
J 2
(-3250 4500);
DISPLAY 0.787234 (-3250 4500);
PAINT MONO (-3250 4500);
DISPLAY INVISIBLE (-3250 4500);
FORCEPROP 1 LAST BODY_TYPE PLUMBING
J 0
(-3250 4450);
DISPLAY 1.234043 (-3250 4450);
PAINT GREEN (-3250 4450);
DISPLAY INVISIBLE (-3250 4450);
FORCEPROP 1 LAST HDL_TAP TRUE
J 0
(-2925 4375);
DISPLAY 1.234043 (-2925 4375);
PAINT GREEN (-2925 4375);
DISPLAY INVISIBLE (-2925 4375);
FORCEPROP 1 LAST PATH I120
J 0
(-3250 4500);
DISPLAY 0.936170 (-3250 4500);
PAINT GREEN (-3250 4500);
DISPLAY INVISIBLE (-3250 4500);
FORCEADD TAP..6
(-3250 4450);
FORCEPROP 3 LASTPIN (-3200 4450) SIG_NAME M_L_MA<8>
J 0
(-3190 4460);
DISPLAY 0.659574 (-3190 4460);
PAINT MONO (-3190 4460);
DISPLAY INVISIBLE (-3190 4460);
FORCEPROP 1 LASTPIN (-3200 4450) BN 8
J 0
(-3250 4460);
DISPLAY 0.617021 (-3250 4460);
PAINT PINK (-3250 4460);
FORCEPROP 2 LAST CDS_LIB mstr_standard
J 2
(-3250 4450);
DISPLAY 0.787234 (-3250 4450);
PAINT MONO (-3250 4450);
DISPLAY INVISIBLE (-3250 4450);
FORCEPROP 1 LAST BODY_TYPE PLUMBING
J 0
(-3250 4400);
DISPLAY 1.234043 (-3250 4400);
PAINT GREEN (-3250 4400);
DISPLAY INVISIBLE (-3250 4400);
FORCEPROP 1 LAST HDL_TAP TRUE
J 0
(-2925 4325);
DISPLAY 1.234043 (-2925 4325);
PAINT GREEN (-2925 4325);
DISPLAY INVISIBLE (-2925 4325);
FORCEPROP 1 LAST PATH I121
J 0
(-3250 4450);
DISPLAY 0.936170 (-3250 4450);
PAINT GREEN (-3250 4450);
DISPLAY INVISIBLE (-3250 4450);
FORCEADD TAP..6
(-3250 4400);
FORCEPROP 3 LASTPIN (-3200 4400) SIG_NAME M_L_MA<7>
J 0
(-3190 4410);
DISPLAY 0.659574 (-3190 4410);
PAINT MONO (-3190 4410);
DISPLAY INVISIBLE (-3190 4410);
FORCEPROP 1 LASTPIN (-3200 4400) BN 7
J 0
(-3250 4410);
DISPLAY 0.617021 (-3250 4410);
PAINT PINK (-3250 4410);
FORCEPROP 2 LAST CDS_LIB mstr_standard
J 2
(-3250 4400);
DISPLAY 0.787234 (-3250 4400);
PAINT MONO (-3250 4400);
DISPLAY INVISIBLE (-3250 4400);
FORCEPROP 1 LAST BODY_TYPE PLUMBING
J 0
(-3250 4350);
DISPLAY 1.234043 (-3250 4350);
PAINT GREEN (-3250 4350);
DISPLAY INVISIBLE (-3250 4350);
FORCEPROP 1 LAST HDL_TAP TRUE
J 0
(-2925 4275);
DISPLAY 1.234043 (-2925 4275);
PAINT GREEN (-2925 4275);
DISPLAY INVISIBLE (-2925 4275);
FORCEPROP 1 LAST PATH I122
J 0
(-3250 4400);
DISPLAY 0.936170 (-3250 4400);
PAINT GREEN (-3250 4400);
DISPLAY INVISIBLE (-3250 4400);
FORCEADD TAP..6
(-3250 4350);
FORCEPROP 3 LASTPIN (-3200 4350) SIG_NAME M_L_MA<6>
J 0
(-3190 4360);
DISPLAY 0.659574 (-3190 4360);
PAINT MONO (-3190 4360);
DISPLAY INVISIBLE (-3190 4360);
FORCEPROP 1 LASTPIN (-3200 4350) BN 6
J 0
(-3250 4360);
DISPLAY 0.617021 (-3250 4360);
PAINT PINK (-3250 4360);
FORCEPROP 2 LAST CDS_LIB mstr_standard
J 2
(-3250 4350);
DISPLAY 0.787234 (-3250 4350);
PAINT MONO (-3250 4350);
DISPLAY INVISIBLE (-3250 4350);
FORCEPROP 1 LAST BODY_TYPE PLUMBING
J 0
(-3250 4300);
DISPLAY 1.234043 (-3250 4300);
PAINT GREEN (-3250 4300);
DISPLAY INVISIBLE (-3250 4300);
FORCEPROP 1 LAST HDL_TAP TRUE
J 0
(-2925 4225);
DISPLAY 1.234043 (-2925 4225);
PAINT GREEN (-2925 4225);
DISPLAY INVISIBLE (-2925 4225);
FORCEPROP 1 LAST PATH I123
J 0
(-3250 4350);
DISPLAY 0.936170 (-3250 4350);
PAINT GREEN (-3250 4350);
DISPLAY INVISIBLE (-3250 4350);
FORCEADD TAP..6
(-3250 4300);
FORCEPROP 3 LASTPIN (-3200 4300) SIG_NAME M_L_MA<5>
J 0
(-3190 4310);
DISPLAY 0.659574 (-3190 4310);
PAINT MONO (-3190 4310);
DISPLAY INVISIBLE (-3190 4310);
FORCEPROP 1 LASTPIN (-3200 4300) BN 5
J 0
(-3250 4310);
DISPLAY 0.617021 (-3250 4310);
PAINT PINK (-3250 4310);
FORCEPROP 2 LAST CDS_LIB mstr_standard
J 2
(-3250 4300);
DISPLAY 0.787234 (-3250 4300);
PAINT MONO (-3250 4300);
DISPLAY INVISIBLE (-3250 4300);
FORCEPROP 1 LAST BODY_TYPE PLUMBING
J 0
(-3250 4250);
DISPLAY 1.234043 (-3250 4250);
PAINT GREEN (-3250 4250);
DISPLAY INVISIBLE (-3250 4250);
FORCEPROP 1 LAST HDL_TAP TRUE
J 0
(-2925 4175);
DISPLAY 1.234043 (-2925 4175);
PAINT GREEN (-2925 4175);
DISPLAY INVISIBLE (-2925 4175);
FORCEPROP 1 LAST PATH I124
J 0
(-3250 4300);
DISPLAY 0.936170 (-3250 4300);
PAINT GREEN (-3250 4300);
DISPLAY INVISIBLE (-3250 4300);
FORCEADD TAP..6
(-3250 4250);
FORCEPROP 3 LASTPIN (-3200 4250) SIG_NAME M_L_MA<4>
J 0
(-3190 4260);
DISPLAY 0.659574 (-3190 4260);
PAINT MONO (-3190 4260);
DISPLAY INVISIBLE (-3190 4260);
FORCEPROP 1 LASTPIN (-3200 4250) BN 4
J 0
(-3250 4260);
DISPLAY 0.617021 (-3250 4260);
PAINT PINK (-3250 4260);
FORCEPROP 2 LAST CDS_LIB mstr_standard
J 2
(-3250 4250);
DISPLAY 0.787234 (-3250 4250);
PAINT MONO (-3250 4250);
DISPLAY INVISIBLE (-3250 4250);
FORCEPROP 1 LAST BODY_TYPE PLUMBING
J 0
(-3250 4200);
DISPLAY 1.234043 (-3250 4200);
PAINT GREEN (-3250 4200);
DISPLAY INVISIBLE (-3250 4200);
FORCEPROP 1 LAST HDL_TAP TRUE
J 0
(-2925 4125);
DISPLAY 1.234043 (-2925 4125);
PAINT GREEN (-2925 4125);
DISPLAY INVISIBLE (-2925 4125);
FORCEPROP 1 LAST PATH I125
J 0
(-3250 4250);
DISPLAY 0.936170 (-3250 4250);
PAINT GREEN (-3250 4250);
DISPLAY INVISIBLE (-3250 4250);
FORCEADD TAP..6
(-3250 4150);
FORCEPROP 3 LASTPIN (-3200 4150) SIG_NAME M_L_MA<2>
J 0
(-3190 4160);
DISPLAY 0.659574 (-3190 4160);
PAINT MONO (-3190 4160);
DISPLAY INVISIBLE (-3190 4160);
FORCEPROP 1 LASTPIN (-3200 4150) BN 2
J 0
(-3250 4160);
DISPLAY 0.617021 (-3250 4160);
PAINT PINK (-3250 4160);
FORCEPROP 2 LAST CDS_LIB mstr_standard
J 2
(-3250 4150);
DISPLAY 0.787234 (-3250 4150);
PAINT MONO (-3250 4150);
DISPLAY INVISIBLE (-3250 4150);
FORCEPROP 1 LAST BODY_TYPE PLUMBING
J 0
(-3250 4100);
DISPLAY 1.234043 (-3250 4100);
PAINT GREEN (-3250 4100);
DISPLAY INVISIBLE (-3250 4100);
FORCEPROP 1 LAST HDL_TAP TRUE
J 0
(-2925 4025);
DISPLAY 1.234043 (-2925 4025);
PAINT GREEN (-2925 4025);
DISPLAY INVISIBLE (-2925 4025);
FORCEPROP 1 LAST PATH I126
J 0
(-3250 4150);
DISPLAY 0.936170 (-3250 4150);
PAINT GREEN (-3250 4150);
DISPLAY INVISIBLE (-3250 4150);
FORCEADD TAP..6
(-3250 4200);
FORCEPROP 3 LASTPIN (-3200 4200) SIG_NAME M_L_MA<3>
J 0
(-3190 4210);
DISPLAY 0.659574 (-3190 4210);
PAINT MONO (-3190 4210);
DISPLAY INVISIBLE (-3190 4210);
FORCEPROP 1 LASTPIN (-3200 4200) BN 3
J 0
(-3250 4210);
DISPLAY 0.617021 (-3250 4210);
PAINT PINK (-3250 4210);
FORCEPROP 2 LAST CDS_LIB mstr_standard
J 2
(-3250 4200);
DISPLAY 0.787234 (-3250 4200);
PAINT MONO (-3250 4200);
DISPLAY INVISIBLE (-3250 4200);
FORCEPROP 1 LAST BODY_TYPE PLUMBING
J 0
(-3250 4150);
DISPLAY 1.234043 (-3250 4150);
PAINT GREEN (-3250 4150);
DISPLAY INVISIBLE (-3250 4150);
FORCEPROP 1 LAST HDL_TAP TRUE
J 0
(-2925 4075);
DISPLAY 1.234043 (-2925 4075);
PAINT GREEN (-2925 4075);
DISPLAY INVISIBLE (-2925 4075);
FORCEPROP 1 LAST PATH I127
J 0
(-3250 4200);
DISPLAY 0.936170 (-3250 4200);
PAINT GREEN (-3250 4200);
DISPLAY INVISIBLE (-3250 4200);
FORCEADD TAP..6
(-3250 4100);
FORCEPROP 3 LASTPIN (-3200 4100) SIG_NAME M_L_MA<1>
J 0
(-3190 4110);
DISPLAY 0.659574 (-3190 4110);
PAINT MONO (-3190 4110);
DISPLAY INVISIBLE (-3190 4110);
FORCEPROP 1 LASTPIN (-3200 4100) BN 1
J 0
(-3250 4110);
DISPLAY 0.617021 (-3250 4110);
PAINT PINK (-3250 4110);
FORCEPROP 2 LAST CDS_LIB mstr_standard
J 2
(-3250 4100);
DISPLAY 0.787234 (-3250 4100);
PAINT MONO (-3250 4100);
DISPLAY INVISIBLE (-3250 4100);
FORCEPROP 1 LAST BODY_TYPE PLUMBING
J 0
(-3250 4050);
DISPLAY 1.234043 (-3250 4050);
PAINT GREEN (-3250 4050);
DISPLAY INVISIBLE (-3250 4050);
FORCEPROP 1 LAST HDL_TAP TRUE
J 0
(-2925 3975);
DISPLAY 1.234043 (-2925 3975);
PAINT GREEN (-2925 3975);
DISPLAY INVISIBLE (-2925 3975);
FORCEPROP 1 LAST PATH I128
J 0
(-3250 4100);
DISPLAY 0.936170 (-3250 4100);
PAINT GREEN (-3250 4100);
DISPLAY INVISIBLE (-3250 4100);
FORCEADD TAP..6
(-3250 4050);
FORCEPROP 3 LASTPIN (-3200 4050) SIG_NAME M_L_MA<0>
J 0
(-3190 4060);
DISPLAY 0.659574 (-3190 4060);
PAINT MONO (-3190 4060);
DISPLAY INVISIBLE (-3190 4060);
FORCEPROP 1 LASTPIN (-3200 4050) BN 0
J 0
(-3250 4060);
DISPLAY 0.617021 (-3250 4060);
PAINT PINK (-3250 4060);
FORCEPROP 2 LAST CDS_LIB mstr_standard
J 2
(-3250 4050);
DISPLAY 0.787234 (-3250 4050);
PAINT MONO (-3250 4050);
DISPLAY INVISIBLE (-3250 4050);
FORCEPROP 1 LAST BODY_TYPE PLUMBING
J 0
(-3250 4000);
DISPLAY 1.234043 (-3250 4000);
PAINT GREEN (-3250 4000);
DISPLAY INVISIBLE (-3250 4000);
FORCEPROP 1 LAST HDL_TAP TRUE
J 0
(-2925 3925);
DISPLAY 1.234043 (-2925 3925);
PAINT GREEN (-2925 3925);
DISPLAY INVISIBLE (-2925 3925);
FORCEPROP 1 LAST PATH I129
J 0
(-3250 4050);
DISPLAY 0.936170 (-3250 4050);
PAINT GREEN (-3250 4050);
DISPLAY INVISIBLE (-3250 4050);
FORCEADD TAP..6
R 2
(700 4550);
FORCEPROP 3 LASTPIN (650 4550) SIG_NAME M_L_DQS_DP<11>
J 0
(660 4560);
DISPLAY 0.659574 (660 4560);
PAINT MONO (660 4560);
DISPLAY INVISIBLE (660 4560);
FORCEPROP 1 LASTPIN (650 4550) BN 11
J 2
(700 4560);
DISPLAY 0.617021 (700 4560);
PAINT PINK (700 4560);
FORCEPROP 2 LAST CDS_LIB mstr_standard
J 0
(700 4550);
DISPLAY 0.787234 (700 4550);
PAINT MONO (700 4550);
DISPLAY INVISIBLE (700 4550);
FORCEPROP 1 LAST BODY_TYPE PLUMBING
J 2
(700 4500);
DISPLAY 1.234043 (700 4500);
PAINT GREEN (700 4500);
DISPLAY INVISIBLE (700 4500);
FORCEPROP 1 LAST HDL_TAP TRUE
J 2
(375 4425);
DISPLAY 1.234043 (375 4425);
PAINT GREEN (375 4425);
DISPLAY INVISIBLE (375 4425);
FORCEPROP 1 LAST PATH I13
J 2
(700 4550);
DISPLAY 0.936170 (700 4550);
PAINT GREEN (700 4550);
DISPLAY INVISIBLE (700 4550);
FORCEADD TAP..6
(-3250 3950);
FORCEPROP 3 LASTPIN (-3200 3950) SIG_NAME M_L_BA<1>
J 0
(-3190 3960);
DISPLAY 0.659574 (-3190 3960);
PAINT MONO (-3190 3960);
DISPLAY INVISIBLE (-3190 3960);
FORCEPROP 1 LASTPIN (-3200 3950) BN 1
J 0
(-3250 3960);
DISPLAY 0.617021 (-3250 3960);
PAINT PINK (-3250 3960);
FORCEPROP 2 LAST CDS_LIB mstr_standard
J 0
(-3250 3950);
DISPLAY 0.787234 (-3250 3950);
PAINT MONO (-3250 3950);
DISPLAY INVISIBLE (-3250 3950);
FORCEPROP 1 LAST BODY_TYPE PLUMBING
J 0
(-3250 3900);
DISPLAY 1.234043 (-3250 3900);
PAINT GREEN (-3250 3900);
DISPLAY INVISIBLE (-3250 3900);
FORCEPROP 1 LAST HDL_TAP TRUE
J 0
(-2925 3825);
DISPLAY 1.234043 (-2925 3825);
PAINT GREEN (-2925 3825);
DISPLAY INVISIBLE (-2925 3825);
FORCEPROP 1 LAST PATH I130
J 0
(-3250 3950);
DISPLAY 0.936170 (-3250 3950);
PAINT GREEN (-3250 3950);
DISPLAY INVISIBLE (-3250 3950);
FORCEADD OFFPAGE..1
(-3850 4950);
FORCEPROP 2 LAST $XR1 86 
J 0
(-4191 4950);
DISPLAY 0.638298 (-4191 4950);
PAINT MONO (-4191 4950);
FORCEPROP 2 LAST $XR0 61 
J 0
(-4101 4950);
DISPLAY 0.638298 (-4101 4950);
PAINT MONO (-4101 4950);
FORCEPROP 2 LAST CDS_LIB mstr_standard
J 0
(-3850 4950);
DISPLAY 0.787234 (-3850 4950);
PAINT MONO (-3850 4950);
DISPLAY INVISIBLE (-3850 4950);
FORCEPROP 1 LAST OFFPAGE TRUE
J 0
(-3525 4825);
DISPLAY 0.936170 (-3525 4825);
PAINT GREEN (-3525 4825);
DISPLAY INVISIBLE (-3525 4825);
FORCEPROP 1 LAST COMMENT_BODY TRUE
J 0
(-3725 4850);
DISPLAY 0.936170 (-3725 4850);
PAINT GREEN (-3725 4850);
DISPLAY INVISIBLE (-3725 4850);
FORCEPROP 2 LAST PATH I131
J 0
(-3800 5025);
DISPLAY 0.787234 (-3800 5025);
PAINT MONO (-3800 5025);
DISPLAY INVISIBLE (-3800 5025);
FORCEADD OFFPAGE..1
(-3850 4000);
FORCEPROP 2 LAST $XR0 61 
J 0
(-4101 4000);
DISPLAY 0.638298 (-4101 4000);
PAINT MONO (-4101 4000);
FORCEPROP 2 LAST $XR1 86 
J 0
(-4191 4000);
DISPLAY 0.638298 (-4191 4000);
PAINT MONO (-4191 4000);
FORCEPROP 2 LAST CDS_LIB mstr_standard
J 0
(-3850 4000);
DISPLAY 0.787234 (-3850 4000);
PAINT MONO (-3850 4000);
DISPLAY INVISIBLE (-3850 4000);
FORCEPROP 1 LAST OFFPAGE TRUE
J 0
(-3525 3875);
DISPLAY 0.936170 (-3525 3875);
PAINT GREEN (-3525 3875);
DISPLAY INVISIBLE (-3525 3875);
FORCEPROP 1 LAST COMMENT_BODY TRUE
J 0
(-3725 3900);
DISPLAY 0.936170 (-3725 3900);
PAINT GREEN (-3725 3900);
DISPLAY INVISIBLE (-3725 3900);
FORCEPROP 2 LAST PATH I132
J 0
(-3800 4075);
DISPLAY 0.787234 (-3800 4075);
PAINT MONO (-3800 4075);
DISPLAY INVISIBLE (-3800 4075);
FORCEADD TAP..6
(-3250 3900);
FORCEPROP 3 LASTPIN (-3200 3900) SIG_NAME M_L_BA<0>
J 0
(-3190 3910);
DISPLAY 0.659574 (-3190 3910);
PAINT MONO (-3190 3910);
DISPLAY INVISIBLE (-3190 3910);
FORCEPROP 1 LASTPIN (-3200 3900) BN 0
J 0
(-3250 3910);
DISPLAY 0.617021 (-3250 3910);
PAINT PINK (-3250 3910);
FORCEPROP 2 LAST CDS_LIB mstr_standard
J 0
(-3250 3900);
DISPLAY 0.787234 (-3250 3900);
PAINT MONO (-3250 3900);
DISPLAY INVISIBLE (-3250 3900);
FORCEPROP 1 LAST BODY_TYPE PLUMBING
J 0
(-3250 3850);
DISPLAY 1.234043 (-3250 3850);
PAINT GREEN (-3250 3850);
DISPLAY INVISIBLE (-3250 3850);
FORCEPROP 1 LAST HDL_TAP TRUE
J 0
(-2925 3775);
DISPLAY 1.234043 (-2925 3775);
PAINT GREEN (-2925 3775);
DISPLAY INVISIBLE (-2925 3775);
FORCEPROP 1 LAST PATH I133
J 0
(-3250 3900);
DISPLAY 0.936170 (-3250 3900);
PAINT GREEN (-3250 3900);
DISPLAY INVISIBLE (-3250 3900);
FORCEADD TAP..6
(-3250 3850);
FORCEPROP 3 LASTPIN (-3200 3850) SIG_NAME M_L_BG<1>
J 0
(-3190 3860);
DISPLAY 0.659574 (-3190 3860);
PAINT MONO (-3190 3860);
DISPLAY INVISIBLE (-3190 3860);
FORCEPROP 1 LASTPIN (-3200 3850) BN 1
J 0
(-3250 3860);
DISPLAY 0.617021 (-3250 3860);
PAINT PINK (-3250 3860);
FORCEPROP 2 LAST CDS_LIB mstr_standard
J 0
(-3250 3850);
DISPLAY 0.787234 (-3250 3850);
PAINT MONO (-3250 3850);
DISPLAY INVISIBLE (-3250 3850);
FORCEPROP 1 LAST BODY_TYPE PLUMBING
J 0
(-3250 3800);
DISPLAY 1.234043 (-3250 3800);
PAINT GREEN (-3250 3800);
DISPLAY INVISIBLE (-3250 3800);
FORCEPROP 1 LAST HDL_TAP TRUE
J 0
(-2925 3725);
DISPLAY 1.234043 (-2925 3725);
PAINT GREEN (-2925 3725);
DISPLAY INVISIBLE (-2925 3725);
FORCEPROP 1 LAST PATH I134
J 0
(-3250 3850);
DISPLAY 0.936170 (-3250 3850);
PAINT GREEN (-3250 3850);
DISPLAY INVISIBLE (-3250 3850);
FORCEADD TAP..6
(-3250 3800);
FORCEPROP 3 LASTPIN (-3200 3800) SIG_NAME M_L_BG<0>
J 0
(-3190 3810);
DISPLAY 0.659574 (-3190 3810);
PAINT MONO (-3190 3810);
DISPLAY INVISIBLE (-3190 3810);
FORCEPROP 1 LASTPIN (-3200 3800) BN 0
J 0
(-3250 3810);
DISPLAY 0.617021 (-3250 3810);
PAINT PINK (-3250 3810);
FORCEPROP 2 LAST CDS_LIB mstr_standard
J 0
(-3250 3800);
DISPLAY 0.787234 (-3250 3800);
PAINT MONO (-3250 3800);
DISPLAY INVISIBLE (-3250 3800);
FORCEPROP 1 LAST BODY_TYPE PLUMBING
J 0
(-3250 3750);
DISPLAY 1.234043 (-3250 3750);
PAINT GREEN (-3250 3750);
DISPLAY INVISIBLE (-3250 3750);
FORCEPROP 1 LAST HDL_TAP TRUE
J 0
(-2925 3675);
DISPLAY 1.234043 (-2925 3675);
PAINT GREEN (-2925 3675);
DISPLAY INVISIBLE (-2925 3675);
FORCEPROP 1 LAST PATH I135
J 0
(-3250 3800);
DISPLAY 0.936170 (-3250 3800);
PAINT GREEN (-3250 3800);
DISPLAY INVISIBLE (-3250 3800);
FORCEADD OFFPAGE..1
(-3850 3500);
FORCEPROP 2 LAST $XR1 86 
J 0
(-4191 3500);
DISPLAY 0.638298 (-4191 3500);
PAINT MONO (-4191 3500);
FORCEPROP 2 LAST $XR0 61 
J 0
(-4101 3500);
DISPLAY 0.638298 (-4101 3500);
PAINT MONO (-4101 3500);
FORCEPROP 2 LAST CDS_LIB mstr_standard
J 0
(-3850 3500);
DISPLAY 0.787234 (-3850 3500);
PAINT MONO (-3850 3500);
DISPLAY INVISIBLE (-3850 3500);
FORCEPROP 1 LAST OFFPAGE TRUE
J 0
(-3525 3375);
DISPLAY 0.936170 (-3525 3375);
PAINT GREEN (-3525 3375);
DISPLAY INVISIBLE (-3525 3375);
FORCEPROP 1 LAST COMMENT_BODY TRUE
J 0
(-3725 3400);
DISPLAY 0.936170 (-3725 3400);
PAINT GREEN (-3725 3400);
DISPLAY INVISIBLE (-3725 3400);
FORCEPROP 2 LAST PATH I136
J 0
(-3800 3575);
DISPLAY 0.787234 (-3800 3575);
PAINT MONO (-3800 3575);
DISPLAY INVISIBLE (-3800 3575);
FORCEADD OFFPAGE..1
(-3850 3875);
FORCEPROP 2 LAST $XR1 86 
J 0
(-4191 3875);
DISPLAY 0.638298 (-4191 3875);
PAINT MONO (-4191 3875);
FORCEPROP 2 LAST $XR0 61 
J 0
(-4101 3875);
DISPLAY 0.638298 (-4101 3875);
PAINT MONO (-4101 3875);
FORCEPROP 2 LAST CDS_LIB mstr_standard
J 0
(-3850 3875);
DISPLAY 0.787234 (-3850 3875);
PAINT MONO (-3850 3875);
DISPLAY INVISIBLE (-3850 3875);
FORCEPROP 1 LAST OFFPAGE TRUE
J 0
(-3525 3750);
DISPLAY 0.936170 (-3525 3750);
PAINT GREEN (-3525 3750);
DISPLAY INVISIBLE (-3525 3750);
FORCEPROP 1 LAST COMMENT_BODY TRUE
J 0
(-3725 3775);
DISPLAY 0.936170 (-3725 3775);
PAINT GREEN (-3725 3775);
DISPLAY INVISIBLE (-3725 3775);
FORCEPROP 2 LAST PATH I137
J 0
(-3800 3950);
DISPLAY 0.787234 (-3800 3950);
PAINT MONO (-3800 3950);
DISPLAY INVISIBLE (-3800 3950);
FORCEADD TAP..6
(-3250 2850);
FORCEPROP 3 LASTPIN (-3200 2850) SIG_NAME M_L_ECC<6>
J 0
(-3190 2860);
DISPLAY 0.659574 (-3190 2860);
PAINT MONO (-3190 2860);
DISPLAY INVISIBLE (-3190 2860);
FORCEPROP 1 LASTPIN (-3200 2850) BN 6
J 0
(-3250 2860);
DISPLAY 0.617021 (-3250 2860);
PAINT PINK (-3250 2860);
FORCEPROP 2 LAST CDS_LIB mstr_standard
J 0
(-3250 2850);
DISPLAY 0.787234 (-3250 2850);
PAINT MONO (-3250 2850);
DISPLAY INVISIBLE (-3250 2850);
FORCEPROP 1 LAST BODY_TYPE PLUMBING
J 0
(-3250 2800);
DISPLAY 1.234043 (-3250 2800);
PAINT GREEN (-3250 2800);
DISPLAY INVISIBLE (-3250 2800);
FORCEPROP 1 LAST HDL_TAP TRUE
J 0
(-2925 2725);
DISPLAY 1.234043 (-2925 2725);
PAINT GREEN (-2925 2725);
DISPLAY INVISIBLE (-2925 2725);
FORCEPROP 1 LAST PATH I138
J 0
(-3250 2850);
DISPLAY 0.936170 (-3250 2850);
PAINT GREEN (-3250 2850);
DISPLAY INVISIBLE (-3250 2850);
FORCEADD TAP..6
(-3250 2800);
FORCEPROP 3 LASTPIN (-3200 2800) SIG_NAME M_L_ECC<7>
J 0
(-3190 2810);
DISPLAY 0.659574 (-3190 2810);
PAINT MONO (-3190 2810);
DISPLAY INVISIBLE (-3190 2810);
FORCEPROP 1 LASTPIN (-3200 2800) BN 7
J 0
(-3250 2810);
DISPLAY 0.617021 (-3250 2810);
PAINT PINK (-3250 2810);
FORCEPROP 2 LAST CDS_LIB mstr_standard
J 0
(-3250 2800);
DISPLAY 0.787234 (-3250 2800);
PAINT MONO (-3250 2800);
DISPLAY INVISIBLE (-3250 2800);
FORCEPROP 1 LAST BODY_TYPE PLUMBING
J 0
(-3250 2750);
DISPLAY 1.234043 (-3250 2750);
PAINT GREEN (-3250 2750);
DISPLAY INVISIBLE (-3250 2750);
FORCEPROP 1 LAST HDL_TAP TRUE
J 0
(-2925 2675);
DISPLAY 1.234043 (-2925 2675);
PAINT GREEN (-2925 2675);
DISPLAY INVISIBLE (-2925 2675);
FORCEPROP 1 LAST PATH I139
J 0
(-3250 2800);
DISPLAY 0.936170 (-3250 2800);
PAINT GREEN (-3250 2800);
DISPLAY INVISIBLE (-3250 2800);
FORCEADD TAP..6
R 2
(700 4650);
FORCEPROP 3 LASTPIN (650 4650) SIG_NAME M_L_DQS_DP<12>
J 0
(660 4660);
DISPLAY 0.659574 (660 4660);
PAINT MONO (660 4660);
DISPLAY INVISIBLE (660 4660);
FORCEPROP 1 LASTPIN (650 4650) BN 12
J 2
(700 4660);
DISPLAY 0.617021 (700 4660);
PAINT PINK (700 4660);
FORCEPROP 2 LAST CDS_LIB mstr_standard
J 0
(700 4650);
DISPLAY 0.787234 (700 4650);
PAINT MONO (700 4650);
DISPLAY INVISIBLE (700 4650);
FORCEPROP 1 LAST BODY_TYPE PLUMBING
J 2
(700 4600);
DISPLAY 1.234043 (700 4600);
PAINT GREEN (700 4600);
DISPLAY INVISIBLE (700 4600);
FORCEPROP 1 LAST HDL_TAP TRUE
J 2
(375 4525);
DISPLAY 1.234043 (375 4525);
PAINT GREEN (375 4525);
DISPLAY INVISIBLE (375 4525);
FORCEPROP 1 LAST PATH I14
J 2
(700 4650);
DISPLAY 0.936170 (700 4650);
PAINT GREEN (700 4650);
DISPLAY INVISIBLE (700 4650);
FORCEADD TAP..6
(-3250 2750);
FORCEPROP 3 LASTPIN (-3200 2750) SIG_NAME M_L_ECC<4>
J 0
(-3190 2760);
DISPLAY 0.659574 (-3190 2760);
PAINT MONO (-3190 2760);
DISPLAY INVISIBLE (-3190 2760);
FORCEPROP 1 LASTPIN (-3200 2750) BN 4
J 0
(-3250 2760);
DISPLAY 0.617021 (-3250 2760);
PAINT PINK (-3250 2760);
FORCEPROP 2 LAST CDS_LIB mstr_standard
J 0
(-3250 2750);
DISPLAY 0.787234 (-3250 2750);
PAINT MONO (-3250 2750);
DISPLAY INVISIBLE (-3250 2750);
FORCEPROP 1 LAST BODY_TYPE PLUMBING
J 0
(-3250 2700);
DISPLAY 1.234043 (-3250 2700);
PAINT GREEN (-3250 2700);
DISPLAY INVISIBLE (-3250 2700);
FORCEPROP 1 LAST HDL_TAP TRUE
J 0
(-2925 2625);
DISPLAY 1.234043 (-2925 2625);
PAINT GREEN (-2925 2625);
DISPLAY INVISIBLE (-2925 2625);
FORCEPROP 1 LAST PATH I140
J 0
(-3250 2750);
DISPLAY 0.936170 (-3250 2750);
PAINT GREEN (-3250 2750);
DISPLAY INVISIBLE (-3250 2750);
FORCEADD TAP..6
(-3250 2700);
FORCEPROP 3 LASTPIN (-3200 2700) SIG_NAME M_L_ECC<5>
J 0
(-3190 2710);
DISPLAY 0.659574 (-3190 2710);
PAINT MONO (-3190 2710);
DISPLAY INVISIBLE (-3190 2710);
FORCEPROP 1 LASTPIN (-3200 2700) BN 5
J 0
(-3250 2710);
DISPLAY 0.617021 (-3250 2710);
PAINT PINK (-3250 2710);
FORCEPROP 2 LAST CDS_LIB mstr_standard
J 0
(-3250 2700);
DISPLAY 0.787234 (-3250 2700);
PAINT MONO (-3250 2700);
DISPLAY INVISIBLE (-3250 2700);
FORCEPROP 1 LAST BODY_TYPE PLUMBING
J 0
(-3250 2650);
DISPLAY 1.234043 (-3250 2650);
PAINT GREEN (-3250 2650);
DISPLAY INVISIBLE (-3250 2650);
FORCEPROP 1 LAST HDL_TAP TRUE
J 0
(-2925 2575);
DISPLAY 1.234043 (-2925 2575);
PAINT GREEN (-2925 2575);
DISPLAY INVISIBLE (-2925 2575);
FORCEPROP 1 LAST PATH I141
J 0
(-3250 2700);
DISPLAY 0.936170 (-3250 2700);
PAINT GREEN (-3250 2700);
DISPLAY INVISIBLE (-3250 2700);
FORCEADD TAP..6
(-3250 2650);
FORCEPROP 3 LASTPIN (-3200 2650) SIG_NAME M_L_ECC<2>
J 0
(-3190 2660);
DISPLAY 0.659574 (-3190 2660);
PAINT MONO (-3190 2660);
DISPLAY INVISIBLE (-3190 2660);
FORCEPROP 1 LASTPIN (-3200 2650) BN 2
J 0
(-3250 2660);
DISPLAY 0.617021 (-3250 2660);
PAINT PINK (-3250 2660);
FORCEPROP 2 LAST CDS_LIB mstr_standard
J 0
(-3250 2650);
DISPLAY 0.787234 (-3250 2650);
PAINT MONO (-3250 2650);
DISPLAY INVISIBLE (-3250 2650);
FORCEPROP 1 LAST BODY_TYPE PLUMBING
J 0
(-3250 2600);
DISPLAY 1.234043 (-3250 2600);
PAINT GREEN (-3250 2600);
DISPLAY INVISIBLE (-3250 2600);
FORCEPROP 1 LAST HDL_TAP TRUE
J 0
(-2925 2525);
DISPLAY 1.234043 (-2925 2525);
PAINT GREEN (-2925 2525);
DISPLAY INVISIBLE (-2925 2525);
FORCEPROP 1 LAST PATH I142
J 0
(-3250 2650);
DISPLAY 0.936170 (-3250 2650);
PAINT GREEN (-3250 2650);
DISPLAY INVISIBLE (-3250 2650);
FORCEADD TAP..6
(-3250 2600);
FORCEPROP 3 LASTPIN (-3200 2600) SIG_NAME M_L_ECC<3>
J 0
(-3190 2610);
DISPLAY 0.659574 (-3190 2610);
PAINT MONO (-3190 2610);
DISPLAY INVISIBLE (-3190 2610);
FORCEPROP 1 LASTPIN (-3200 2600) BN 3
J 0
(-3250 2610);
DISPLAY 0.617021 (-3250 2610);
PAINT PINK (-3250 2610);
FORCEPROP 2 LAST CDS_LIB mstr_standard
J 0
(-3250 2600);
DISPLAY 0.787234 (-3250 2600);
PAINT MONO (-3250 2600);
DISPLAY INVISIBLE (-3250 2600);
FORCEPROP 1 LAST BODY_TYPE PLUMBING
J 0
(-3250 2550);
DISPLAY 1.234043 (-3250 2550);
PAINT GREEN (-3250 2550);
DISPLAY INVISIBLE (-3250 2550);
FORCEPROP 1 LAST HDL_TAP TRUE
J 0
(-2925 2475);
DISPLAY 1.234043 (-2925 2475);
PAINT GREEN (-2925 2475);
DISPLAY INVISIBLE (-2925 2475);
FORCEPROP 1 LAST PATH I143
J 0
(-3250 2600);
DISPLAY 0.936170 (-3250 2600);
PAINT GREEN (-3250 2600);
DISPLAY INVISIBLE (-3250 2600);
FORCEADD TAP..6
(-3250 2550);
FORCEPROP 3 LASTPIN (-3200 2550) SIG_NAME M_L_ECC<0>
J 0
(-3190 2560);
DISPLAY 0.659574 (-3190 2560);
PAINT MONO (-3190 2560);
DISPLAY INVISIBLE (-3190 2560);
FORCEPROP 1 LASTPIN (-3200 2550) BN 0
J 0
(-3250 2560);
DISPLAY 0.617021 (-3250 2560);
PAINT PINK (-3250 2560);
FORCEPROP 2 LAST CDS_LIB mstr_standard
J 0
(-3250 2550);
DISPLAY 0.787234 (-3250 2550);
PAINT MONO (-3250 2550);
DISPLAY INVISIBLE (-3250 2550);
FORCEPROP 1 LAST BODY_TYPE PLUMBING
J 0
(-3250 2500);
DISPLAY 1.234043 (-3250 2500);
PAINT GREEN (-3250 2500);
DISPLAY INVISIBLE (-3250 2500);
FORCEPROP 1 LAST HDL_TAP TRUE
J 0
(-2925 2425);
DISPLAY 1.234043 (-2925 2425);
PAINT GREEN (-2925 2425);
DISPLAY INVISIBLE (-2925 2425);
FORCEPROP 1 LAST PATH I144
J 0
(-3250 2550);
DISPLAY 0.936170 (-3250 2550);
PAINT GREEN (-3250 2550);
DISPLAY INVISIBLE (-3250 2550);
FORCEADD TAP..6
(-3250 2500);
FORCEPROP 3 LASTPIN (-3200 2500) SIG_NAME M_L_ECC<1>
J 0
(-3190 2510);
DISPLAY 0.659574 (-3190 2510);
PAINT MONO (-3190 2510);
DISPLAY INVISIBLE (-3190 2510);
FORCEPROP 1 LASTPIN (-3200 2500) BN 1
J 0
(-3250 2510);
DISPLAY 0.617021 (-3250 2510);
PAINT PINK (-3250 2510);
FORCEPROP 2 LAST CDS_LIB mstr_standard
J 0
(-3250 2500);
DISPLAY 0.787234 (-3250 2500);
PAINT MONO (-3250 2500);
DISPLAY INVISIBLE (-3250 2500);
FORCEPROP 1 LAST BODY_TYPE PLUMBING
J 0
(-3250 2450);
DISPLAY 1.234043 (-3250 2450);
PAINT GREEN (-3250 2450);
DISPLAY INVISIBLE (-3250 2450);
FORCEPROP 1 LAST HDL_TAP TRUE
J 0
(-2925 2375);
DISPLAY 1.234043 (-2925 2375);
PAINT GREEN (-2925 2375);
DISPLAY INVISIBLE (-2925 2375);
FORCEPROP 1 LAST PATH I145
J 0
(-3250 2500);
DISPLAY 0.936170 (-3250 2500);
PAINT GREEN (-3250 2500);
DISPLAY INVISIBLE (-3250 2500);
FORCEADD OFFPAGE..1
(-3850 2850);
FORCEPROP 2 LAST $XR1 86 
J 0
(-4191 2850);
DISPLAY 0.638298 (-4191 2850);
PAINT MONO (-4191 2850);
FORCEPROP 2 LAST $XR0 61 
J 0
(-4101 2850);
DISPLAY 0.638298 (-4101 2850);
PAINT MONO (-4101 2850);
FORCEPROP 2 LAST CDS_LIB mstr_standard
J 0
(-3850 2850);
DISPLAY 0.787234 (-3850 2850);
PAINT MONO (-3850 2850);
DISPLAY INVISIBLE (-3850 2850);
FORCEPROP 1 LAST OFFPAGE TRUE
J 0
(-3525 2725);
DISPLAY 0.936170 (-3525 2725);
PAINT GREEN (-3525 2725);
DISPLAY INVISIBLE (-3525 2725);
FORCEPROP 1 LAST COMMENT_BODY TRUE
J 0
(-3725 2750);
DISPLAY 0.936170 (-3725 2750);
PAINT GREEN (-3725 2750);
DISPLAY INVISIBLE (-3725 2750);
FORCEPROP 2 LAST PATH I146
J 0
(-3800 2925);
DISPLAY 0.787234 (-3800 2925);
PAINT MONO (-3800 2925);
DISPLAY INVISIBLE (-3800 2925);
FORCEADD OFFPAGE..1
(-4050 2200);
FORCEPROP 2 LAST $XR1 86 
J 0
(-4391 2200);
DISPLAY 0.638298 (-4391 2200);
PAINT MONO (-4391 2200);
FORCEPROP 2 LAST $XR0 61 
J 0
(-4301 2200);
DISPLAY 0.638298 (-4301 2200);
PAINT MONO (-4301 2200);
FORCEPROP 2 LAST CDS_LIB mstr_standard
J 0
(-4050 2200);
DISPLAY 0.787234 (-4050 2200);
PAINT MONO (-4050 2200);
DISPLAY INVISIBLE (-4050 2200);
FORCEPROP 1 LAST OFFPAGE TRUE
J 0
(-3725 2075);
DISPLAY 0.936170 (-3725 2075);
PAINT GREEN (-3725 2075);
DISPLAY INVISIBLE (-3725 2075);
FORCEPROP 1 LAST COMMENT_BODY TRUE
J 0
(-3925 2100);
DISPLAY 0.936170 (-3925 2100);
PAINT GREEN (-3925 2100);
DISPLAY INVISIBLE (-3925 2100);
FORCEPROP 2 LAST PATH I147
J 0
(-4000 2275);
DISPLAY 0.787234 (-4000 2275);
PAINT MONO (-4000 2275);
DISPLAY INVISIBLE (-4000 2275);
FORCEADD OFFPAGE..5
(-4075 2250);
FORCEPROP 2 LAST $XR1 61 
J 0
(-4389 2250);
DISPLAY 0.638298 (-4389 2250);
PAINT MONO (-4389 2250);
FORCEPROP 2 LAST $XR0 86 
J 0
(-4299 2250);
DISPLAY 0.638298 (-4299 2250);
PAINT MONO (-4299 2250);
FORCEPROP 2 LAST CDS_LIB mstr_standard
J 0
(-4075 2250);
DISPLAY 0.787234 (-4075 2250);
PAINT MONO (-4075 2250);
DISPLAY INVISIBLE (-4075 2250);
FORCEPROP 1 LAST OFFPAGE TRUE
J 0
(-3750 2125);
DISPLAY 1.404255 (-3750 2125);
PAINT GREEN (-3750 2125);
DISPLAY INVISIBLE (-3750 2125);
FORCEPROP 1 LAST COMMENT_BODY TRUE
J 0
(-3975 2175);
DISPLAY 1.404255 (-3975 2175);
PAINT GREEN (-3975 2175);
DISPLAY INVISIBLE (-3975 2175);
FORCEPROP 2 LAST PATH I148
J 0
(-4025 2325);
DISPLAY 0.787234 (-4025 2325);
PAINT MONO (-4025 2325);
DISPLAY INVISIBLE (-4025 2325);
FORCEADD OFFPAGE..1
(-3850 2800);
FORCEPROP 2 LAST $XR5 88 
J 0
(-4551 2800);
DISPLAY 0.638298 (-4551 2800);
PAINT MONO (-4551 2800);
FORCEPROP 2 LAST $XR4 87 
J 0
(-4461 2800);
DISPLAY 0.638298 (-4461 2800);
PAINT MONO (-4461 2800);
FORCEPROP 2 LAST $XR3 86 
J 0
(-4371 2800);
DISPLAY 0.638298 (-4371 2800);
PAINT MONO (-4371 2800);
FORCEPROP 2 LAST $XR2 84 
J 0
(-4281 2800);
DISPLAY 0.638298 (-4281 2800);
PAINT MONO (-4281 2800);
FORCEPROP 2 LAST $XR1 83 
J 0
(-4191 2800);
DISPLAY 0.638298 (-4191 2800);
PAINT MONO (-4191 2800);
FORCEPROP 2 LAST $XR0 55 
J 0
(-4101 2800);
DISPLAY 0.638298 (-4101 2800);
PAINT MONO (-4101 2800);
FORCEPROP 2 LAST CDS_LIB mstr_standard
J 0
(-3850 2800);
DISPLAY 0.787234 (-3850 2800);
PAINT MONO (-3850 2800);
DISPLAY INVISIBLE (-3850 2800);
FORCEPROP 1 LAST OFFPAGE TRUE
J 0
(-3525 2675);
DISPLAY 0.936170 (-3525 2675);
PAINT GREEN (-3525 2675);
DISPLAY INVISIBLE (-3525 2675);
FORCEPROP 1 LAST COMMENT_BODY TRUE
J 0
(-3725 2700);
DISPLAY 0.936170 (-3725 2700);
PAINT GREEN (-3725 2700);
DISPLAY INVISIBLE (-3725 2700);
FORCEPROP 2 LAST PATH I149
J 0
(-3800 2875);
DISPLAY 0.787234 (-3800 2875);
PAINT MONO (-3800 2875);
DISPLAY INVISIBLE (-3800 2875);
FORCEADD TAP..6
R 2
(700 4750);
FORCEPROP 3 LASTPIN (650 4750) SIG_NAME M_L_DQS_DP<13>
J 0
(660 4760);
DISPLAY 0.659574 (660 4760);
PAINT MONO (660 4760);
DISPLAY INVISIBLE (660 4760);
FORCEPROP 1 LASTPIN (650 4750) BN 13
J 2
(700 4760);
DISPLAY 0.617021 (700 4760);
PAINT PINK (700 4760);
FORCEPROP 2 LAST CDS_LIB mstr_standard
J 0
(700 4750);
DISPLAY 0.787234 (700 4750);
PAINT MONO (700 4750);
DISPLAY INVISIBLE (700 4750);
FORCEPROP 1 LAST BODY_TYPE PLUMBING
J 2
(700 4700);
DISPLAY 1.234043 (700 4700);
PAINT GREEN (700 4700);
DISPLAY INVISIBLE (700 4700);
FORCEPROP 1 LAST HDL_TAP TRUE
J 2
(375 4625);
DISPLAY 1.234043 (375 4625);
PAINT GREEN (375 4625);
DISPLAY INVISIBLE (375 4625);
FORCEPROP 1 LAST PATH I15
J 2
(700 4750);
DISPLAY 0.936170 (700 4750);
PAINT GREEN (700 4750);
DISPLAY INVISIBLE (700 4750);
FORCEADD OFFPAGE..6
(-3850 2900);
FORCEPROP 2 LAST $XR1 86 
J 0
(-4189 2900);
DISPLAY 0.638298 (-4189 2900);
PAINT MONO (-4189 2900);
FORCEPROP 2 LAST $XR0 61 
J 0
(-4099 2900);
DISPLAY 0.638298 (-4099 2900);
PAINT MONO (-4099 2900);
FORCEPROP 2 LAST CDS_LIB mstr_standard
J 0
(-3850 2900);
DISPLAY 0.787234 (-3850 2900);
PAINT MONO (-3850 2900);
DISPLAY INVISIBLE (-3850 2900);
FORCEPROP 1 LAST OFFPAGE TRUE
J 0
(-3525 2775);
DISPLAY 0.936170 (-3525 2775);
PAINT GREEN (-3525 2775);
DISPLAY INVISIBLE (-3525 2775);
FORCEPROP 1 LAST COMMENT_BODY TRUE
J 0
(-3750 2825);
DISPLAY 0.936170 (-3750 2825);
PAINT GREEN (-3750 2825);
DISPLAY INVISIBLE (-3750 2825);
FORCEPROP 2 LAST PATH I150
J 0
(-3800 2975);
DISPLAY 0.787234 (-3800 2975);
PAINT MONO (-3800 2975);
DISPLAY INVISIBLE (-3800 2975);
FORCEADD TAP..6
(-3250 3700);
FORCEPROP 3 LASTPIN (-3200 3700) SIG_NAME M_L_CLK_DP<1>
J 0
(-3190 3710);
DISPLAY 0.659574 (-3190 3710);
PAINT MONO (-3190 3710);
DISPLAY INVISIBLE (-3190 3710);
FORCEPROP 1 LASTPIN (-3200 3700) BN 1
J 0
(-3250 3710);
DISPLAY 0.617021 (-3250 3710);
PAINT PINK (-3250 3710);
FORCEPROP 2 LAST CDS_LIB mstr_standard
J 0
(-3250 3700);
DISPLAY 0.787234 (-3250 3700);
PAINT MONO (-3250 3700);
DISPLAY INVISIBLE (-3250 3700);
FORCEPROP 1 LAST BODY_TYPE PLUMBING
J 0
(-3250 3650);
DISPLAY 1.234043 (-3250 3650);
PAINT GREEN (-3250 3650);
DISPLAY INVISIBLE (-3250 3650);
FORCEPROP 1 LAST HDL_TAP TRUE
J 0
(-2925 3575);
DISPLAY 1.234043 (-2925 3575);
PAINT GREEN (-2925 3575);
DISPLAY INVISIBLE (-2925 3575);
FORCEPROP 1 LAST PATH I152
J 0
(-3250 3700);
DISPLAY 0.936170 (-3250 3700);
PAINT GREEN (-3250 3700);
DISPLAY INVISIBLE (-3250 3700);
FORCEADD TAP..6
(-3250 3600);
FORCEPROP 3 LASTPIN (-3200 3600) SIG_NAME M_L_CLK_DP<0>
J 0
(-3190 3610);
DISPLAY 0.659574 (-3190 3610);
PAINT MONO (-3190 3610);
DISPLAY INVISIBLE (-3190 3610);
FORCEPROP 1 LASTPIN (-3200 3600) BN 0
J 0
(-3250 3610);
DISPLAY 0.617021 (-3250 3610);
PAINT PINK (-3250 3610);
FORCEPROP 2 LAST CDS_LIB mstr_standard
J 0
(-3250 3600);
DISPLAY 0.787234 (-3250 3600);
PAINT MONO (-3250 3600);
DISPLAY INVISIBLE (-3250 3600);
FORCEPROP 1 LAST BODY_TYPE PLUMBING
J 0
(-3250 3550);
DISPLAY 1.234043 (-3250 3550);
PAINT GREEN (-3250 3550);
DISPLAY INVISIBLE (-3250 3550);
FORCEPROP 1 LAST HDL_TAP TRUE
J 0
(-2925 3475);
DISPLAY 1.234043 (-2925 3475);
PAINT GREEN (-2925 3475);
DISPLAY INVISIBLE (-2925 3475);
FORCEPROP 1 LAST PATH I153
J 0
(-3250 3600);
DISPLAY 0.936170 (-3250 3600);
PAINT GREEN (-3250 3600);
DISPLAY INVISIBLE (-3250 3600);
FORCEADD TAP..6
(-3450 3650);
FORCEPROP 3 LASTPIN (-3400 3650) SIG_NAME M_L_CLK_DN<1>
J 0
(-3390 3660);
DISPLAY 0.659574 (-3390 3660);
PAINT MONO (-3390 3660);
DISPLAY INVISIBLE (-3390 3660);
FORCEPROP 1 LASTPIN (-3400 3650) BN 1
J 0
(-3450 3660);
DISPLAY 0.617021 (-3450 3660);
PAINT PINK (-3450 3660);
FORCEPROP 2 LAST CDS_LIB mstr_standard
J 0
(-3450 3650);
DISPLAY 0.787234 (-3450 3650);
PAINT MONO (-3450 3650);
DISPLAY INVISIBLE (-3450 3650);
FORCEPROP 1 LAST BODY_TYPE PLUMBING
J 0
(-3450 3600);
DISPLAY 1.234043 (-3450 3600);
PAINT GREEN (-3450 3600);
DISPLAY INVISIBLE (-3450 3600);
FORCEPROP 1 LAST HDL_TAP TRUE
J 0
(-3125 3525);
DISPLAY 1.234043 (-3125 3525);
PAINT GREEN (-3125 3525);
DISPLAY INVISIBLE (-3125 3525);
FORCEPROP 1 LAST PATH I154
J 0
(-3450 3650);
DISPLAY 0.936170 (-3450 3650);
PAINT GREEN (-3450 3650);
DISPLAY INVISIBLE (-3450 3650);
FORCEADD TAP..6
(-3450 3550);
FORCEPROP 3 LASTPIN (-3400 3550) SIG_NAME M_L_CLK_DN<0>
J 0
(-3390 3560);
DISPLAY 0.659574 (-3390 3560);
PAINT MONO (-3390 3560);
DISPLAY INVISIBLE (-3390 3560);
FORCEPROP 1 LASTPIN (-3400 3550) BN 0
J 0
(-3450 3560);
DISPLAY 0.617021 (-3450 3560);
PAINT PINK (-3450 3560);
FORCEPROP 2 LAST CDS_LIB mstr_standard
J 0
(-3450 3550);
DISPLAY 0.787234 (-3450 3550);
PAINT MONO (-3450 3550);
DISPLAY INVISIBLE (-3450 3550);
FORCEPROP 1 LAST BODY_TYPE PLUMBING
J 0
(-3450 3500);
DISPLAY 1.234043 (-3450 3500);
PAINT GREEN (-3450 3500);
DISPLAY INVISIBLE (-3450 3500);
FORCEPROP 1 LAST HDL_TAP TRUE
J 0
(-3125 3425);
DISPLAY 1.234043 (-3125 3425);
PAINT GREEN (-3125 3425);
DISPLAY INVISIBLE (-3125 3425);
FORCEPROP 1 LAST PATH I155
J 0
(-3450 3550);
DISPLAY 0.936170 (-3450 3550);
PAINT GREEN (-3450 3550);
DISPLAY INVISIBLE (-3450 3550);
FORCEADD OFFPAGE..1
(-3850 3750);
FORCEPROP 2 LAST $XR1 86 
J 0
(-4191 3750);
DISPLAY 0.638298 (-4191 3750);
PAINT MONO (-4191 3750);
FORCEPROP 2 LAST $XR0 61 
J 0
(-4101 3750);
DISPLAY 0.638298 (-4101 3750);
PAINT MONO (-4101 3750);
FORCEPROP 2 LAST CDS_LIB mstr_standard
J 0
(-3850 3750);
DISPLAY 0.787234 (-3850 3750);
PAINT MONO (-3850 3750);
DISPLAY INVISIBLE (-3850 3750);
FORCEPROP 1 LAST OFFPAGE TRUE
J 0
(-3525 3625);
DISPLAY 0.936170 (-3525 3625);
PAINT GREEN (-3525 3625);
DISPLAY INVISIBLE (-3525 3625);
FORCEPROP 1 LAST COMMENT_BODY TRUE
J 0
(-3725 3650);
DISPLAY 0.936170 (-3725 3650);
PAINT GREEN (-3725 3650);
DISPLAY INVISIBLE (-3725 3650);
FORCEPROP 2 LAST PATH I156
J 0
(-3800 3825);
DISPLAY 0.787234 (-3800 3825);
PAINT MONO (-3800 3825);
DISPLAY INVISIBLE (-3800 3825);
FORCEADD OFFPAGE..1
(-3850 3700);
FORCEPROP 2 LAST $XR1 86 
J 0
(-4191 3700);
DISPLAY 0.638298 (-4191 3700);
PAINT MONO (-4191 3700);
FORCEPROP 2 LAST $XR0 61 
J 0
(-4101 3700);
DISPLAY 0.638298 (-4101 3700);
PAINT MONO (-4101 3700);
FORCEPROP 2 LAST CDS_LIB mstr_standard
J 0
(-3850 3700);
DISPLAY 0.787234 (-3850 3700);
PAINT MONO (-3850 3700);
DISPLAY INVISIBLE (-3850 3700);
FORCEPROP 1 LAST OFFPAGE TRUE
J 0
(-3525 3575);
DISPLAY 0.936170 (-3525 3575);
PAINT GREEN (-3525 3575);
DISPLAY INVISIBLE (-3525 3575);
FORCEPROP 1 LAST COMMENT_BODY TRUE
J 0
(-3725 3600);
DISPLAY 0.936170 (-3725 3600);
PAINT GREEN (-3725 3600);
DISPLAY INVISIBLE (-3725 3600);
FORCEPROP 2 LAST PATH I157
J 0
(-3800 3775);
DISPLAY 0.787234 (-3800 3775);
PAINT MONO (-3800 3775);
DISPLAY INVISIBLE (-3800 3775);
FORCEADD TAP..6
(-3250 3400);
FORCEPROP 3 LASTPIN (-3200 3400) SIG_NAME M_L_CS_N<3>
J 0
(-3190 3410);
DISPLAY 0.659574 (-3190 3410);
PAINT MONO (-3190 3410);
DISPLAY INVISIBLE (-3190 3410);
FORCEPROP 1 LASTPIN (-3200 3400) BN 3
J 0
(-3250 3410);
DISPLAY 0.617021 (-3250 3410);
PAINT PINK (-3250 3410);
FORCEPROP 2 LAST CDS_LIB mstr_standard
J 0
(-3250 3400);
DISPLAY 0.787234 (-3250 3400);
PAINT MONO (-3250 3400);
DISPLAY INVISIBLE (-3250 3400);
FORCEPROP 1 LAST BODY_TYPE PLUMBING
J 0
(-3250 3350);
DISPLAY 1.234043 (-3250 3350);
PAINT GREEN (-3250 3350);
DISPLAY INVISIBLE (-3250 3350);
FORCEPROP 1 LAST HDL_TAP TRUE
J 0
(-2925 3275);
DISPLAY 1.234043 (-2925 3275);
PAINT GREEN (-2925 3275);
DISPLAY INVISIBLE (-2925 3275);
FORCEPROP 1 LAST PATH I159
J 0
(-3250 3400);
DISPLAY 0.936170 (-3250 3400);
PAINT GREEN (-3250 3400);
DISPLAY INVISIBLE (-3250 3400);
FORCEADD PVDDQ_KLM..1
(-1350 2625);
FORCEPROP 3 LASTPIN (-1350 2575) SIG_NAME PVDDQ_KLM\g
J 0
(-1340 2585);
DISPLAY 0.659574 (-1340 2585);
PAINT MONO (-1340 2585);
DISPLAY INVISIBLE (-1340 2585);
FORCEPROP 1 LAST VOLTAGE 1.2V
J 0
(-1395 2582);
DISPLAY 0.340426 (-1395 2582);
PAINT SKYBLUE (-1395 2582);
DISPLAY INVISIBLE (-1395 2582);
FORCEPROP 2 LAST BOM_COST MEM
J 0
(-1350 2630);
PAINT ORANGE (-1350 2630);
DISPLAY INVISIBLE (-1350 2630);
FORCEPROP 2 LAST CDS_LIB mstr_symbols
J 0
(-1350 2625);
PAINT ORANGE (-1350 2625);
DISPLAY INVISIBLE (-1350 2625);
FORCEPROP 1 LAST BODY_TYPE PLUMBING
J 0
(-1395 2582);
DISPLAY 0.340426 (-1395 2582);
PAINT GREEN (-1395 2582);
DISPLAY INVISIBLE (-1395 2582);
FORCEPROP 1 LAST PATH I16
J 0
(-1300 2650);
DISPLAY 0.872340 (-1300 2650);
PAINT AQUA (-1300 2650);
DISPLAY INVISIBLE (-1300 2650);
FORCEPROP 2 LAST ROOM DDR4_CH_D
J 0
(-1350 2725);
DISPLAY 0.787234 (-1350 2725);
PAINT ORANGE (-1350 2725);
DISPLAY INVISIBLE (-1350 2725);
FORCEPROP 1 LAST HDL_POWER PVDDQ_KLM
J 1
(-1350 2675);
DISPLAY 0.872340 (-1350 2675);
PAINT GREEN (-1350 2675);
DISPLAY INVISIBLE (-1350 2675);
FORCEADD TAP..6
(-3250 3350);
FORCEPROP 3 LASTPIN (-3200 3350) SIG_NAME M_L_CS_N<2>
J 0
(-3190 3360);
DISPLAY 0.659574 (-3190 3360);
PAINT MONO (-3190 3360);
DISPLAY INVISIBLE (-3190 3360);
FORCEPROP 1 LASTPIN (-3200 3350) BN 2
J 0
(-3250 3360);
DISPLAY 0.617021 (-3250 3360);
PAINT PINK (-3250 3360);
FORCEPROP 2 LAST CDS_LIB mstr_standard
J 0
(-3250 3350);
DISPLAY 0.787234 (-3250 3350);
PAINT MONO (-3250 3350);
DISPLAY INVISIBLE (-3250 3350);
FORCEPROP 1 LAST BODY_TYPE PLUMBING
J 0
(-3250 3300);
DISPLAY 1.234043 (-3250 3300);
PAINT GREEN (-3250 3300);
DISPLAY INVISIBLE (-3250 3300);
FORCEPROP 1 LAST HDL_TAP TRUE
J 0
(-2925 3225);
DISPLAY 1.234043 (-2925 3225);
PAINT GREEN (-2925 3225);
DISPLAY INVISIBLE (-2925 3225);
FORCEPROP 1 LAST PATH I160
J 0
(-3250 3350);
DISPLAY 0.936170 (-3250 3350);
PAINT GREEN (-3250 3350);
DISPLAY INVISIBLE (-3250 3350);
FORCEADD TAP..6
(-3250 3300);
FORCEPROP 3 LASTPIN (-3200 3300) SIG_NAME M_L_CS_N<1>
J 0
(-3190 3310);
DISPLAY 0.659574 (-3190 3310);
PAINT MONO (-3190 3310);
DISPLAY INVISIBLE (-3190 3310);
FORCEPROP 1 LASTPIN (-3200 3300) BN 1
J 0
(-3250 3310);
DISPLAY 0.617021 (-3250 3310);
PAINT PINK (-3250 3310);
FORCEPROP 2 LAST CDS_LIB mstr_standard
J 0
(-3250 3300);
DISPLAY 0.787234 (-3250 3300);
PAINT MONO (-3250 3300);
DISPLAY INVISIBLE (-3250 3300);
FORCEPROP 1 LAST BODY_TYPE PLUMBING
J 0
(-3250 3250);
DISPLAY 1.234043 (-3250 3250);
PAINT GREEN (-3250 3250);
DISPLAY INVISIBLE (-3250 3250);
FORCEPROP 1 LAST HDL_TAP TRUE
J 0
(-2925 3175);
DISPLAY 1.234043 (-2925 3175);
PAINT GREEN (-2925 3175);
DISPLAY INVISIBLE (-2925 3175);
FORCEPROP 1 LAST PATH I161
J 0
(-3250 3300);
DISPLAY 0.936170 (-3250 3300);
PAINT GREEN (-3250 3300);
DISPLAY INVISIBLE (-3250 3300);
FORCEADD TAP..6
(-3250 3250);
FORCEPROP 3 LASTPIN (-3200 3250) SIG_NAME M_L_CS_N<0>
J 0
(-3190 3260);
DISPLAY 0.659574 (-3190 3260);
PAINT MONO (-3190 3260);
DISPLAY INVISIBLE (-3190 3260);
FORCEPROP 1 LASTPIN (-3200 3250) BN 0
J 0
(-3250 3260);
DISPLAY 0.617021 (-3250 3260);
PAINT PINK (-3250 3260);
FORCEPROP 2 LAST CDS_LIB mstr_standard
J 0
(-3250 3250);
DISPLAY 0.787234 (-3250 3250);
PAINT MONO (-3250 3250);
DISPLAY INVISIBLE (-3250 3250);
FORCEPROP 1 LAST BODY_TYPE PLUMBING
J 0
(-3250 3200);
DISPLAY 1.234043 (-3250 3200);
PAINT GREEN (-3250 3200);
DISPLAY INVISIBLE (-3250 3200);
FORCEPROP 1 LAST HDL_TAP TRUE
J 0
(-2925 3125);
DISPLAY 1.234043 (-2925 3125);
PAINT GREEN (-2925 3125);
DISPLAY INVISIBLE (-2925 3125);
FORCEPROP 1 LAST PATH I162
J 0
(-3250 3250);
DISPLAY 0.936170 (-3250 3250);
PAINT GREEN (-3250 3250);
DISPLAY INVISIBLE (-3250 3250);
FORCEADD TAP..6
(-3250 3150);
FORCEPROP 3 LASTPIN (-3200 3150) SIG_NAME M_L_CKE<1>
J 0
(-3190 3160);
DISPLAY 0.659574 (-3190 3160);
PAINT MONO (-3190 3160);
DISPLAY INVISIBLE (-3190 3160);
FORCEPROP 1 LASTPIN (-3200 3150) BN 1
J 0
(-3250 3160);
DISPLAY 0.617021 (-3250 3160);
PAINT PINK (-3250 3160);
FORCEPROP 2 LAST CDS_LIB mstr_standard
J 0
(-3250 3150);
DISPLAY 0.787234 (-3250 3150);
PAINT MONO (-3250 3150);
DISPLAY INVISIBLE (-3250 3150);
FORCEPROP 1 LAST BODY_TYPE PLUMBING
J 0
(-3250 3100);
DISPLAY 1.234043 (-3250 3100);
PAINT GREEN (-3250 3100);
DISPLAY INVISIBLE (-3250 3100);
FORCEPROP 1 LAST HDL_TAP TRUE
J 0
(-2925 3025);
DISPLAY 1.234043 (-2925 3025);
PAINT GREEN (-2925 3025);
DISPLAY INVISIBLE (-2925 3025);
FORCEPROP 1 LAST PATH I163
J 0
(-3250 3150);
DISPLAY 0.936170 (-3250 3150);
PAINT GREEN (-3250 3150);
DISPLAY INVISIBLE (-3250 3150);
FORCEADD OFFPAGE..1
(-3850 3450);
FORCEPROP 2 LAST $XR1 86 
J 0
(-4191 3450);
DISPLAY 0.638298 (-4191 3450);
PAINT MONO (-4191 3450);
FORCEPROP 2 LAST $XR0 61 
J 0
(-4101 3450);
DISPLAY 0.638298 (-4101 3450);
PAINT MONO (-4101 3450);
FORCEPROP 2 LAST CDS_LIB mstr_standard
J 0
(-3850 3450);
DISPLAY 0.787234 (-3850 3450);
PAINT MONO (-3850 3450);
DISPLAY INVISIBLE (-3850 3450);
FORCEPROP 1 LAST OFFPAGE TRUE
J 0
(-3525 3325);
DISPLAY 0.936170 (-3525 3325);
PAINT GREEN (-3525 3325);
DISPLAY INVISIBLE (-3525 3325);
FORCEPROP 1 LAST COMMENT_BODY TRUE
J 0
(-3725 3350);
DISPLAY 0.936170 (-3725 3350);
PAINT GREEN (-3725 3350);
DISPLAY INVISIBLE (-3725 3350);
FORCEPROP 2 LAST PATH I164
J 0
(-3800 3525);
DISPLAY 0.787234 (-3800 3525);
PAINT MONO (-3800 3525);
DISPLAY INVISIBLE (-3800 3525);
FORCEADD OFFPAGE..1
(-3850 3200);
FORCEPROP 2 LAST $XR1 86 
J 0
(-4191 3200);
DISPLAY 0.638298 (-4191 3200);
PAINT MONO (-4191 3200);
FORCEPROP 2 LAST $XR0 61 
J 0
(-4101 3200);
DISPLAY 0.638298 (-4101 3200);
PAINT MONO (-4101 3200);
FORCEPROP 2 LAST CDS_LIB mstr_standard
J 0
(-3850 3200);
DISPLAY 0.787234 (-3850 3200);
PAINT MONO (-3850 3200);
DISPLAY INVISIBLE (-3850 3200);
FORCEPROP 1 LAST OFFPAGE TRUE
J 0
(-3525 3075);
DISPLAY 0.936170 (-3525 3075);
PAINT GREEN (-3525 3075);
DISPLAY INVISIBLE (-3525 3075);
FORCEPROP 1 LAST COMMENT_BODY TRUE
J 0
(-3725 3100);
DISPLAY 0.936170 (-3725 3100);
PAINT GREEN (-3725 3100);
DISPLAY INVISIBLE (-3725 3100);
FORCEPROP 2 LAST PATH I165
J 0
(-3800 3275);
DISPLAY 0.787234 (-3800 3275);
PAINT MONO (-3800 3275);
DISPLAY INVISIBLE (-3800 3275);
FORCEADD TAP..6
(-3250 3100);
FORCEPROP 3 LASTPIN (-3200 3100) SIG_NAME M_L_CKE<0>
J 0
(-3190 3110);
DISPLAY 0.659574 (-3190 3110);
PAINT MONO (-3190 3110);
DISPLAY INVISIBLE (-3190 3110);
FORCEPROP 1 LASTPIN (-3200 3100) BN 0
J 0
(-3250 3110);
DISPLAY 0.617021 (-3250 3110);
PAINT PINK (-3250 3110);
FORCEPROP 2 LAST CDS_LIB mstr_standard
J 0
(-3250 3100);
DISPLAY 0.787234 (-3250 3100);
PAINT MONO (-3250 3100);
DISPLAY INVISIBLE (-3250 3100);
FORCEPROP 1 LAST BODY_TYPE PLUMBING
J 0
(-3250 3050);
DISPLAY 1.234043 (-3250 3050);
PAINT GREEN (-3250 3050);
DISPLAY INVISIBLE (-3250 3050);
FORCEPROP 1 LAST HDL_TAP TRUE
J 0
(-2925 2975);
DISPLAY 1.234043 (-2925 2975);
PAINT GREEN (-2925 2975);
DISPLAY INVISIBLE (-2925 2975);
FORCEPROP 1 LAST PATH I166
J 0
(-3250 3100);
DISPLAY 0.936170 (-3250 3100);
PAINT GREEN (-3250 3100);
DISPLAY INVISIBLE (-3250 3100);
FORCEADD TAP..6
(-3250 3000);
FORCEPROP 3 LASTPIN (-3200 3000) SIG_NAME M_L_ODT<1>
J 0
(-3190 3010);
DISPLAY 0.659574 (-3190 3010);
PAINT MONO (-3190 3010);
DISPLAY INVISIBLE (-3190 3010);
FORCEPROP 1 LASTPIN (-3200 3000) BN 1
J 0
(-3250 3010);
DISPLAY 0.617021 (-3250 3010);
PAINT PINK (-3250 3010);
FORCEPROP 2 LAST CDS_LIB mstr_standard
J 0
(-3250 3000);
DISPLAY 0.787234 (-3250 3000);
PAINT MONO (-3250 3000);
DISPLAY INVISIBLE (-3250 3000);
FORCEPROP 1 LAST BODY_TYPE PLUMBING
J 0
(-3250 2950);
DISPLAY 1.234043 (-3250 2950);
PAINT GREEN (-3250 2950);
DISPLAY INVISIBLE (-3250 2950);
FORCEPROP 1 LAST HDL_TAP TRUE
J 0
(-2925 2875);
DISPLAY 1.234043 (-2925 2875);
PAINT GREEN (-2925 2875);
DISPLAY INVISIBLE (-2925 2875);
FORCEPROP 1 LAST PATH I167
J 0
(-3250 3000);
DISPLAY 0.936170 (-3250 3000);
PAINT GREEN (-3250 3000);
DISPLAY INVISIBLE (-3250 3000);
FORCEADD TAP..6
(-3250 2950);
FORCEPROP 3 LASTPIN (-3200 2950) SIG_NAME M_L_ODT<0>
J 0
(-3190 2960);
DISPLAY 0.659574 (-3190 2960);
PAINT MONO (-3190 2960);
DISPLAY INVISIBLE (-3190 2960);
FORCEPROP 1 LASTPIN (-3200 2950) BN 0
J 0
(-3250 2960);
DISPLAY 0.617021 (-3250 2960);
PAINT PINK (-3250 2960);
FORCEPROP 2 LAST CDS_LIB mstr_standard
J 0
(-3250 2950);
DISPLAY 0.787234 (-3250 2950);
PAINT MONO (-3250 2950);
DISPLAY INVISIBLE (-3250 2950);
FORCEPROP 1 LAST BODY_TYPE PLUMBING
J 0
(-3250 2900);
DISPLAY 1.234043 (-3250 2900);
PAINT GREEN (-3250 2900);
DISPLAY INVISIBLE (-3250 2900);
FORCEPROP 1 LAST HDL_TAP TRUE
J 0
(-2925 2825);
DISPLAY 1.234043 (-2925 2825);
PAINT GREEN (-2925 2825);
DISPLAY INVISIBLE (-2925 2825);
FORCEPROP 1 LAST PATH I168
J 0
(-3250 2950);
DISPLAY 0.936170 (-3250 2950);
PAINT GREEN (-3250 2950);
DISPLAY INVISIBLE (-3250 2950);
FORCEADD OFFPAGE..1
(-3850 3050);
FORCEPROP 2 LAST $XR1 86 
J 0
(-4191 3050);
DISPLAY 0.638298 (-4191 3050);
PAINT MONO (-4191 3050);
FORCEPROP 2 LAST $XR0 61 
J 0
(-4101 3050);
DISPLAY 0.638298 (-4101 3050);
PAINT MONO (-4101 3050);
FORCEPROP 2 LAST CDS_LIB mstr_standard
J 0
(-3850 3050);
DISPLAY 0.787234 (-3850 3050);
PAINT MONO (-3850 3050);
DISPLAY INVISIBLE (-3850 3050);
FORCEPROP 1 LAST OFFPAGE TRUE
J 0
(-3525 2925);
DISPLAY 0.936170 (-3525 2925);
PAINT GREEN (-3525 2925);
DISPLAY INVISIBLE (-3525 2925);
FORCEPROP 1 LAST COMMENT_BODY TRUE
J 0
(-3725 2950);
DISPLAY 0.936170 (-3725 2950);
PAINT GREEN (-3725 2950);
DISPLAY INVISIBLE (-3725 2950);
FORCEPROP 2 LAST PATH I169
J 0
(-3800 3125);
DISPLAY 0.787234 (-3800 3125);
PAINT MONO (-3800 3125);
DISPLAY INVISIBLE (-3800 3125);
FORCEADD PVTT_KLM..1
(-1100 2750);
FORCEPROP 3 LASTPIN (-1100 2700) SIG_NAME PVTT_KLM\g
J 0
(-1090 2710);
DISPLAY 0.659574 (-1090 2710);
PAINT MONO (-1090 2710);
DISPLAY INVISIBLE (-1090 2710);
FORCEPROP 1 LAST VOLTAGE 0.6V
J 0
(-1145 2707);
DISPLAY 0.340426 (-1145 2707);
PAINT SKYBLUE (-1145 2707);
DISPLAY INVISIBLE (-1145 2707);
FORCEPROP 2 LAST BOM_COST MEM
J 0
(-1100 2755);
PAINT ORANGE (-1100 2755);
DISPLAY INVISIBLE (-1100 2755);
FORCEPROP 2 LAST CDS_LIB mstr_symbols
J 0
(-1100 2750);
PAINT ORANGE (-1100 2750);
DISPLAY INVISIBLE (-1100 2750);
FORCEPROP 1 LAST BODY_TYPE PLUMBING
J 0
(-1145 2707);
DISPLAY 0.340426 (-1145 2707);
PAINT GREEN (-1145 2707);
DISPLAY INVISIBLE (-1145 2707);
FORCEPROP 1 LAST PATH I17
J 0
(-1050 2775);
DISPLAY 0.872340 (-1050 2775);
PAINT AQUA (-1050 2775);
DISPLAY INVISIBLE (-1050 2775);
FORCEPROP 2 LAST ROOM DDR4_CH_D
J 0
(-1100 2850);
DISPLAY 0.787234 (-1100 2850);
PAINT ORANGE (-1100 2850);
DISPLAY INVISIBLE (-1100 2850);
FORCEPROP 1 LAST HDL_POWER PVTT_KLM
J 1
(-1100 2800);
DISPLAY 0.872340 (-1100 2800);
PAINT GREEN (-1100 2800);
DISPLAY INVISIBLE (-1100 2800);
FORCEADD SCONN288_H44441004..4
(-250 2050);
FORCEPROP 1 LAST LOCATION J1A2
J 0
(-700 3150);
DISPLAY 0.617021 (-700 3150);
PAINT AQUA (-700 3150);
FORCEPROP 1 LAST PART_NUMBER H44441-004
J 0
(-700 1000);
DISPLAY 0.617021 (-700 1000);
PAINT BLUE (-700 1000);
FORCEPROP 1 LAST MATERIAL SCONN
J 0
(-700 3100);
DISPLAY 0.617021 (-700 3100);
PAINT SKYBLUE (-700 3100);
FORCEPROP 2 LASTPIN (-750 2600) $PN 77
J 2
(-760 2610);
DISPLAY 0.617021 (-760 2610);
PAINT ORANGE (-760 2610);
FORCEPROP 2 LASTPIN (-750 2550) $PN 221
J 2
(-760 2560);
DISPLAY 0.617021 (-760 2560);
PAINT ORANGE (-760 2560);
FORCEPROP 2 LASTPIN (-750 2900) $PN 142
J 2
(-760 2910);
DISPLAY 0.617021 (-760 2910);
PAINT ORANGE (-760 2910);
FORCEPROP 2 LASTPIN (-750 2850) $PN 143
J 2
(-760 2860);
DISPLAY 0.617021 (-760 2860);
PAINT ORANGE (-760 2860);
FORCEPROP 2 LASTPIN (-750 2800) $PN 288
J 2
(-760 2810);
DISPLAY 0.617021 (-760 2810);
PAINT ORANGE (-760 2810);
FORCEPROP 2 LASTPIN (-750 2750) $PN 286
J 2
(-760 2760);
DISPLAY 0.617021 (-760 2760);
PAINT ORANGE (-760 2760);
FORCEPROP 2 LASTPIN (-750 2700) $PN 287
J 2
(-760 2710);
DISPLAY 0.617021 (-760 2710);
PAINT ORANGE (-760 2710);
FORCEPROP 2 LASTPIN (-750 2450) $PN 59
J 2
(-760 2460);
DISPLAY 0.617021 (-760 2460);
PAINT ORANGE (-760 2460);
FORCEPROP 2 LASTPIN (-750 2400) $PN 61
J 2
(-760 2410);
DISPLAY 0.617021 (-760 2410);
PAINT ORANGE (-760 2410);
FORCEPROP 2 LASTPIN (-750 2350) $PN 64
J 2
(-760 2360);
DISPLAY 0.617021 (-760 2360);
PAINT ORANGE (-760 2360);
FORCEPROP 2 LASTPIN (-750 2300) $PN 67
J 2
(-760 2310);
DISPLAY 0.617021 (-760 2310);
PAINT ORANGE (-760 2310);
FORCEPROP 2 LASTPIN (-750 2250) $PN 70
J 2
(-760 2260);
DISPLAY 0.617021 (-760 2260);
PAINT ORANGE (-760 2260);
FORCEPROP 2 LASTPIN (-750 2200) $PN 73
J 2
(-760 2210);
DISPLAY 0.617021 (-760 2210);
PAINT ORANGE (-760 2210);
FORCEPROP 2 LASTPIN (-750 2150) $PN 76
J 2
(-760 2160);
DISPLAY 0.617021 (-760 2160);
PAINT ORANGE (-760 2160);
FORCEPROP 2 LASTPIN (-750 2100) $PN 80
J 2
(-760 2110);
DISPLAY 0.617021 (-760 2110);
PAINT ORANGE (-760 2110);
FORCEPROP 2 LASTPIN (-750 2050) $PN 83
J 2
(-760 2060);
DISPLAY 0.617021 (-760 2060);
PAINT ORANGE (-760 2060);
FORCEPROP 2 LASTPIN (-750 2000) $PN 85
J 2
(-760 2010);
DISPLAY 0.617021 (-760 2010);
PAINT ORANGE (-760 2010);
FORCEPROP 2 LASTPIN (-750 1950) $PN 88
J 2
(-760 1960);
DISPLAY 0.617021 (-760 1960);
PAINT ORANGE (-760 1960);
FORCEPROP 2 LASTPIN (-750 1900) $PN 90
J 2
(-760 1910);
DISPLAY 0.617021 (-760 1910);
PAINT ORANGE (-760 1910);
FORCEPROP 2 LASTPIN (-750 1850) $PN 92
J 2
(-760 1860);
DISPLAY 0.617021 (-760 1860);
PAINT ORANGE (-760 1860);
FORCEPROP 2 LASTPIN (-750 1800) $PN 204
J 2
(-760 1810);
DISPLAY 0.617021 (-760 1810);
PAINT ORANGE (-760 1810);
FORCEPROP 2 LASTPIN (-750 1750) $PN 206
J 2
(-760 1760);
DISPLAY 0.617021 (-760 1760);
PAINT ORANGE (-760 1760);
FORCEPROP 2 LASTPIN (-750 1700) $PN 209
J 2
(-760 1710);
DISPLAY 0.617021 (-760 1710);
PAINT ORANGE (-760 1710);
FORCEPROP 2 LASTPIN (-750 1650) $PN 212
J 2
(-760 1660);
DISPLAY 0.617021 (-760 1660);
PAINT ORANGE (-760 1660);
FORCEPROP 2 LASTPIN (-750 1600) $PN 215
J 2
(-760 1610);
DISPLAY 0.617021 (-760 1610);
PAINT ORANGE (-760 1610);
FORCEPROP 2 LASTPIN (-750 1550) $PN 217
J 2
(-760 1560);
DISPLAY 0.617021 (-760 1560);
PAINT ORANGE (-760 1560);
FORCEPROP 2 LASTPIN (-750 1500) $PN 220
J 2
(-760 1510);
DISPLAY 0.617021 (-760 1510);
PAINT ORANGE (-760 1510);
FORCEPROP 2 LASTPIN (-750 1450) $PN 223
J 2
(-760 1460);
DISPLAY 0.617021 (-760 1460);
PAINT ORANGE (-760 1460);
FORCEPROP 2 LASTPIN (-750 1400) $PN 226
J 2
(-760 1410);
DISPLAY 0.617021 (-760 1410);
PAINT ORANGE (-760 1410);
FORCEPROP 2 LASTPIN (-750 1350) $PN 229
J 2
(-760 1360);
DISPLAY 0.617021 (-760 1360);
PAINT ORANGE (-760 1360);
FORCEPROP 2 LASTPIN (-750 1300) $PN 231
J 2
(-760 1310);
DISPLAY 0.617021 (-760 1310);
PAINT ORANGE (-760 1310);
FORCEPROP 2 LASTPIN (-750 1250) $PN 233
J 2
(-760 1260);
DISPLAY 0.617021 (-760 1260);
PAINT ORANGE (-760 1260);
FORCEPROP 2 LASTPIN (-750 1200) $PN 236
J 2
(-760 1210);
DISPLAY 0.617021 (-760 1210);
PAINT ORANGE (-760 1210);
FORCEPROP 2 LASTPIN (250 2900) $PN 1
J 0
(260 2910);
DISPLAY 0.617021 (260 2910);
PAINT ORANGE (260 2910);
FORCEPROP 2 LASTPIN (250 2850) $PN 145
J 0
(260 2860);
DISPLAY 0.617021 (260 2860);
PAINT ORANGE (260 2860);
FORCEPROP 1 LAST PACK_TYPE PIP
J 0
(-700 3200);
PAINT SKYBLUE (-700 3200);
DISPLAY INVISIBLE (-700 3200);
FORCEPROP 2 LAST BOM_COST MEM
J 0
(-250 2050);
PAINT ORANGE (-250 2050);
DISPLAY INVISIBLE (-250 2050);
FORCEPROP 2 LAST CDS_LIB mstr_sconn
J 0
(-250 2050);
PAINT ORANGE (-250 2050);
DISPLAY INVISIBLE (-250 2050);
FORCEPROP 2 LAST SEC_TYPE PIP
J 0
(-700 3200);
DISPLAY 1.021277 (-700 3200);
PAINT ORANGE (-700 3200);
DISPLAY INVISIBLE (-700 3200);
FORCEPROP 2 LAST SEC 4
J 0
(-700 3200);
DISPLAY 0.680851 (-700 3200);
PAINT MONO (-700 3200);
DISPLAY INVISIBLE (-700 3200);
FORCEPROP 2 LAST CDS_LOCATION J1A2
J 0
(-700 3150);
DISPLAY 0.617021 (-700 3150);
PAINT AQUA (-700 3150);
DISPLAY INVISIBLE (-700 3150);
FORCEPROP 1 LAST PATH I172
J 0
(-250 3100);
PAINT GREEN (-250 3100);
DISPLAY INVISIBLE (-250 3100);
FORCEPROP 2 LAST ROOM DDR4_CH_L
J 0
(-250 2050);
PAINT ORANGE (-250 2050);
DISPLAY INVISIBLE (-250 2050);
FORCEADD GND..1
R 2
(2500 1100);
FORCEPROP 3 LASTPIN (2500 1150) SIG_NAME GND\g
J 0
(2510 1160);
DISPLAY 0.659574 (2510 1160);
PAINT MONO (2510 1160);
DISPLAY INVISIBLE (2510 1160);
FORCEPROP 1 LAST VOLTAGE 0
J 0
(2500 1100);
PAINT SKYBLUE (2500 1100);
DISPLAY INVISIBLE (2500 1100);
FORCEPROP 2 LAST BOM_COST MEM
J 0
(2500 1105);
PAINT ORANGE (2500 1105);
DISPLAY INVISIBLE (2500 1105);
FORCEPROP 2 LAST CDS_LIB mstr_symbols
J 0
(2500 1100);
DISPLAY 0.787234 (2500 1100);
PAINT MONO (2500 1100);
DISPLAY INVISIBLE (2500 1100);
FORCEPROP 1 LAST SIZE 1B
J 2
(2425 1050);
DISPLAY 1.170213 (2425 1050);
PAINT GREEN (2425 1050);
DISPLAY INVISIBLE (2425 1050);
FORCEPROP 1 LAST BODY_TYPE PLUMBING
J 2
(2545 1057);
DISPLAY 0.340426 (2545 1057);
PAINT GREEN (2545 1057);
DISPLAY INVISIBLE (2545 1057);
FORCEPROP 1 LAST PATH I173
J 2
(2425 1100);
DISPLAY 1.404255 (2425 1100);
PAINT GREEN (2425 1100);
DISPLAY INVISIBLE (2425 1100);
FORCEPROP 2 LAST ROOM DDR4_CH_D
J 0
(2500 1105);
PAINT ORANGE (2500 1105);
DISPLAY INVISIBLE (2500 1105);
FORCEPROP 1 LAST HDL_POWER GND
J 2
(2500 1250);
DISPLAY 0.553191 (2500 1250);
PAINT GREEN (2500 1250);
DISPLAY INVISIBLE (2500 1250);
FORCEADD GND..1
R 2
(-5150 1850);
FORCEPROP 3 LASTPIN (-5150 1900) SIG_NAME GND\g
J 0
(-5140 1910);
DISPLAY 0.659574 (-5140 1910);
PAINT MONO (-5140 1910);
DISPLAY INVISIBLE (-5140 1910);
FORCEPROP 1 LAST VOLTAGE 0
J 0
(-5150 1850);
PAINT SKYBLUE (-5150 1850);
DISPLAY INVISIBLE (-5150 1850);
FORCEPROP 2 LAST BOM_COST MEM
J 0
(-5150 1855);
PAINT ORANGE (-5150 1855);
DISPLAY INVISIBLE (-5150 1855);
FORCEPROP 1 LAST SIZE 1B
J 2
(-5225 1800);
DISPLAY 1.170213 (-5225 1800);
PAINT GREEN (-5225 1800);
DISPLAY INVISIBLE (-5225 1800);
FORCEPROP 2 LAST CDS_LIB mstr_symbols
J 0
(-5150 1850);
DISPLAY 0.787234 (-5150 1850);
PAINT MONO (-5150 1850);
DISPLAY INVISIBLE (-5150 1850);
FORCEPROP 1 LAST BODY_TYPE PLUMBING
J 2
(-5105 1807);
DISPLAY 0.340426 (-5105 1807);
PAINT GREEN (-5105 1807);
DISPLAY INVISIBLE (-5105 1807);
FORCEPROP 1 LAST PATH I175
J 2
(-5225 1850);
DISPLAY 1.404255 (-5225 1850);
PAINT GREEN (-5225 1850);
DISPLAY INVISIBLE (-5225 1850);
FORCEPROP 2 LAST ROOM DDR4_CH_D
J 0
(-5150 1855);
PAINT ORANGE (-5150 1855);
DISPLAY INVISIBLE (-5150 1855);
FORCEPROP 1 LAST HDL_POWER GND
J 2
(-5150 2000);
DISPLAY 0.553191 (-5150 2000);
PAINT GREEN (-5150 2000);
DISPLAY INVISIBLE (-5150 2000);
FORCEADD OFFPAGE..6
(-3850 1900);
FORCEPROP 2 LASTPIN (-3800 1900) SIG_NAME SMB_DDR_KLM_VPP_SDA
J 0
(-3760 1910);
DISPLAY 0.617021 (-3760 1910);
PAINT ORANGE (-3760 1910);
FORCEPROP 2 LAST $XR5 99 
J 0
(-4549 1900);
DISPLAY 0.638298 (-4549 1900);
PAINT MONO (-4549 1900);
FORCEPROP 2 LAST $XR4 88 
J 0
(-4459 1900);
DISPLAY 0.638298 (-4459 1900);
PAINT MONO (-4459 1900);
FORCEPROP 2 LAST $XR3 87 
J 0
(-4369 1900);
DISPLAY 0.638298 (-4369 1900);
PAINT MONO (-4369 1900);
FORCEPROP 2 LAST $XR2 86 
J 0
(-4279 1900);
DISPLAY 0.638298 (-4279 1900);
PAINT MONO (-4279 1900);
FORCEPROP 2 LAST $XR1 84 
J 0
(-4189 1900);
DISPLAY 0.638298 (-4189 1900);
PAINT MONO (-4189 1900);
FORCEPROP 2 LAST $XR0 83 
J 0
(-4099 1900);
DISPLAY 0.638298 (-4099 1900);
PAINT MONO (-4099 1900);
FORCEPROP 2 LAST CDS_LIB mstr_standard
J 0
(-3850 1900);
DISPLAY 0.787234 (-3850 1900);
PAINT MONO (-3850 1900);
DISPLAY INVISIBLE (-3850 1900);
FORCEPROP 1 LAST OFFPAGE TRUE
J 0
(-3525 1775);
DISPLAY 0.936170 (-3525 1775);
PAINT GREEN (-3525 1775);
DISPLAY INVISIBLE (-3525 1775);
FORCEPROP 1 LAST COMMENT_BODY TRUE
J 0
(-3750 1825);
DISPLAY 0.936170 (-3750 1825);
PAINT GREEN (-3750 1825);
DISPLAY INVISIBLE (-3750 1825);
FORCEPROP 2 LAST PATH I176
J 0
(-4150 1950);
DISPLAY 0.787234 (-4150 1950);
PAINT ORANGE (-4150 1950);
DISPLAY INVISIBLE (-4150 1950);
FORCEADD OFFPAGE..1
(-4800 1750);
FORCEPROP 2 LAST $XR1 86 
J 0
(-5172 1750);
DISPLAY 0.638298 (-5172 1750);
PAINT MONO (-5172 1750);
FORCEPROP 2 LAST $XR0 100 
J 0
(-5082 1750);
DISPLAY 0.638298 (-5082 1750);
PAINT MONO (-5082 1750);
FORCEPROP 2 LAST CDS_LIB mstr_standard
J 0
(-4800 1750);
DISPLAY 0.787234 (-4800 1750);
PAINT MONO (-4800 1750);
DISPLAY INVISIBLE (-4800 1750);
FORCEPROP 1 LAST OFFPAGE TRUE
J 0
(-4475 1625);
DISPLAY 0.936170 (-4475 1625);
PAINT GREEN (-4475 1625);
DISPLAY INVISIBLE (-4475 1625);
FORCEPROP 1 LAST COMMENT_BODY TRUE
J 0
(-4675 1650);
DISPLAY 0.936170 (-4675 1650);
PAINT GREEN (-4675 1650);
DISPLAY INVISIBLE (-4675 1650);
FORCEPROP 2 LAST PATH I177
J 0
(-5050 1800);
DISPLAY 0.787234 (-5050 1800);
PAINT ORANGE (-5050 1800);
DISPLAY INVISIBLE (-5050 1800);
FORCEADD OFFPAGE..1
(-3850 1850);
FORCEPROP 2 LAST $XR5 88 
J 0
(-4551 1850);
DISPLAY 0.638298 (-4551 1850);
PAINT MONO (-4551 1850);
FORCEPROP 2 LAST $XR4 87 
J 0
(-4461 1850);
DISPLAY 0.638298 (-4461 1850);
PAINT MONO (-4461 1850);
FORCEPROP 2 LAST $XR3 86 
J 0
(-4371 1850);
DISPLAY 0.638298 (-4371 1850);
PAINT MONO (-4371 1850);
FORCEPROP 2 LAST $XR2 84 
J 0
(-4281 1850);
DISPLAY 0.638298 (-4281 1850);
PAINT MONO (-4281 1850);
FORCEPROP 2 LAST $XR1 83 
J 0
(-4191 1850);
DISPLAY 0.638298 (-4191 1850);
PAINT MONO (-4191 1850);
FORCEPROP 2 LAST $XR0 99 
J 0
(-4101 1850);
DISPLAY 0.638298 (-4101 1850);
PAINT MONO (-4101 1850);
FORCEPROP 2 LAST CDS_LIB mstr_standard
J 0
(-3850 1850);
DISPLAY 0.787234 (-3850 1850);
PAINT MONO (-3850 1850);
DISPLAY INVISIBLE (-3850 1850);
FORCEPROP 1 LAST OFFPAGE TRUE
J 0
(-3525 1725);
DISPLAY 0.936170 (-3525 1725);
PAINT GREEN (-3525 1725);
DISPLAY INVISIBLE (-3525 1725);
FORCEPROP 1 LAST COMMENT_BODY TRUE
J 0
(-3725 1750);
DISPLAY 0.936170 (-3725 1750);
PAINT GREEN (-3725 1750);
DISPLAY INVISIBLE (-3725 1750);
FORCEPROP 2 LAST PATH I178
J 0
(-4125 1900);
DISPLAY 0.787234 (-4125 1900);
PAINT ORANGE (-4125 1900);
DISPLAY INVISIBLE (-4125 1900);
FORCEADD OFFPAGE..5
(-4225 2550);
FORCEPROP 2 LAST $XR23 94 
J 0
(-4719 2586);
DISPLAY 0.638298 (-4719 2586);
PAINT MONO (-4719 2586);
FORCEPROP 2 LAST $XR22 88 
J 0
(-4629 2586);
DISPLAY 0.638298 (-4629 2586);
PAINT MONO (-4629 2586);
FORCEPROP 2 LAST $XR21 87 
J 0
(-4539 2586);
DISPLAY 0.638298 (-4539 2586);
PAINT MONO (-4539 2586);
FORCEPROP 2 LAST $XR20 86 
J 0
(-4449 2586);
DISPLAY 0.638298 (-4449 2586);
PAINT MONO (-4449 2586);
FORCEPROP 2 LAST $XR19 84 
J 0
(-5259 2514);
DISPLAY 0.638298 (-5259 2514);
PAINT MONO (-5259 2514);
FORCEPROP 2 LAST $XR18 83 
J 0
(-5169 2514);
DISPLAY 0.638298 (-5169 2514);
PAINT MONO (-5169 2514);
FORCEPROP 2 LAST $XR17 82 
J 0
(-5079 2514);
DISPLAY 0.638298 (-5079 2514);
PAINT MONO (-5079 2514);
FORCEPROP 2 LAST $XR16 81 
J 0
(-4989 2514);
DISPLAY 0.638298 (-4989 2514);
PAINT MONO (-4989 2514);
FORCEPROP 2 LAST $XR15 80 
J 0
(-4899 2514);
DISPLAY 0.638298 (-4899 2514);
PAINT MONO (-4899 2514);
FORCEPROP 2 LAST $XR14 79 
J 0
(-4809 2514);
DISPLAY 0.638298 (-4809 2514);
PAINT MONO (-4809 2514);
FORCEPROP 2 LAST $XR13 78 
J 0
(-4719 2514);
DISPLAY 0.638298 (-4719 2514);
PAINT MONO (-4719 2514);
FORCEPROP 2 LAST $XR12 77 
J 0
(-4629 2514);
DISPLAY 0.638298 (-4629 2514);
PAINT MONO (-4629 2514);
FORCEPROP 2 LAST $XR11 54 
J 0
(-4539 2514);
DISPLAY 0.638298 (-4539 2514);
PAINT MONO (-4539 2514);
FORCEPROP 2 LAST $XR10 53 
J 0
(-4449 2514);
DISPLAY 0.638298 (-4449 2514);
PAINT MONO (-4449 2514);
FORCEPROP 2 LAST $XR9 52 
J 0
(-5259 2550);
DISPLAY 0.638298 (-5259 2550);
PAINT MONO (-5259 2550);
FORCEPROP 2 LAST $XR8 51 
J 0
(-5169 2550);
DISPLAY 0.638298 (-5169 2550);
PAINT MONO (-5169 2550);
FORCEPROP 2 LAST $XR7 50 
J 0
(-5079 2550);
DISPLAY 0.638298 (-5079 2550);
PAINT MONO (-5079 2550);
FORCEPROP 2 LAST $XR6 49 
J 0
(-4989 2550);
DISPLAY 0.638298 (-4989 2550);
PAINT MONO (-4989 2550);
FORCEPROP 2 LAST $XR5 48 
J 0
(-4899 2550);
DISPLAY 0.638298 (-4899 2550);
PAINT MONO (-4899 2550);
FORCEPROP 2 LAST $XR4 47 
J 0
(-4809 2550);
DISPLAY 0.638298 (-4809 2550);
PAINT MONO (-4809 2550);
FORCEPROP 2 LAST $XR3 46 
J 0
(-4719 2550);
DISPLAY 0.638298 (-4719 2550);
PAINT MONO (-4719 2550);
FORCEPROP 2 LAST $XR2 45 
J 0
(-4629 2550);
DISPLAY 0.638298 (-4629 2550);
PAINT MONO (-4629 2550);
FORCEPROP 2 LAST $XR1 44 
J 0
(-4539 2550);
DISPLAY 0.638298 (-4539 2550);
PAINT MONO (-4539 2550);
FORCEPROP 2 LAST $XR0 43 
J 0
(-4449 2550);
DISPLAY 0.638298 (-4449 2550);
PAINT MONO (-4449 2550);
FORCEPROP 2 LAST CDS_LIB mstr_standard
J 0
(-4225 2550);
DISPLAY 0.787234 (-4225 2550);
PAINT MONO (-4225 2550);
DISPLAY INVISIBLE (-4225 2550);
FORCEPROP 1 LAST OFFPAGE TRUE
J 0
(-3900 2425);
DISPLAY 1.404255 (-3900 2425);
PAINT GREEN (-3900 2425);
DISPLAY INVISIBLE (-3900 2425);
FORCEPROP 1 LAST COMMENT_BODY TRUE
J 0
(-4125 2475);
DISPLAY 1.404255 (-4125 2475);
PAINT GREEN (-4125 2475);
DISPLAY INVISIBLE (-4125 2475);
FORCEPROP 2 LAST PATH I179
J 0
(-4175 2625);
DISPLAY 0.787234 (-4175 2625);
PAINT ORANGE (-4175 2625);
DISPLAY INVISIBLE (-4175 2625);
FORCEADD GND..1
(-4650 1300);
FORCEPROP 3 LASTPIN (-4650 1350) SIG_NAME GND\g
J 0
(-4640 1360);
DISPLAY 0.659574 (-4640 1360);
PAINT MONO (-4640 1360);
DISPLAY INVISIBLE (-4640 1360);
FORCEPROP 1 LAST VOLTAGE 0
J 0
(-4650 1300);
PAINT SKYBLUE (-4650 1300);
DISPLAY INVISIBLE (-4650 1300);
FORCEPROP 2 LAST BOM_COST MEM
J 0
(-4650 1305);
PAINT ORANGE (-4650 1305);
DISPLAY INVISIBLE (-4650 1305);
FORCEPROP 2 LAST CDS_LIB mstr_symbols
J 0
(-4650 1300);
PAINT ORANGE (-4650 1300);
DISPLAY INVISIBLE (-4650 1300);
FORCEPROP 1 LAST SIZE 1B
J 0
(-4575 1250);
DISPLAY 1.787234 (-4575 1250);
PAINT GREEN (-4575 1250);
DISPLAY INVISIBLE (-4575 1250);
FORCEPROP 1 LAST BODY_TYPE PLUMBING
J 0
(-4695 1257);
DISPLAY 0.340426 (-4695 1257);
PAINT GREEN (-4695 1257);
DISPLAY INVISIBLE (-4695 1257);
FORCEPROP 1 LAST PATH I180
J 0
(-4575 1300);
DISPLAY 1.404255 (-4575 1300);
PAINT GREEN (-4575 1300);
DISPLAY INVISIBLE (-4575 1300);
FORCEPROP 2 LAST ROOM DDR4_CH_D
J 0
(-4650 1305);
PAINT ORANGE (-4650 1305);
DISPLAY INVISIBLE (-4650 1305);
FORCEPROP 1 LAST HDL_POWER GND
J 0
(-4650 1450);
DISPLAY 1.404255 (-4650 1450);
PAINT GREEN (-4650 1450);
DISPLAY INVISIBLE (-4650 1450);
FORCEADD CAP_A..1
R 2
(-4650 1550);
FORCEPROP 1 LAST LOCATION C9L7
J 2
(-4700 1650);
DISPLAY 0.617021 (-4700 1650);
PAINT AQUA (-4700 1650);
FORCEPROP 1 LAST PART_NUMBER A36096-045
J 2
(-4700 1400);
DISPLAY 0.617021 (-4700 1400);
PAINT BLUE (-4700 1400);
FORCEPROP 1 LAST VALUE 0.01UF
J 2
(-4700 1600);
DISPLAY 0.617021 (-4700 1600);
PAINT SKYBLUE (-4700 1600);
FORCEPROP 1 LAST TOLERANCE 10%
J 2
(-4700 1500);
DISPLAY 0.617021 (-4700 1500);
PAINT SKYBLUE (-4700 1500);
FORCEPROP 1 LAST PACK_TYPE 0402V
J 2
(-4700 1350);
DISPLAY 0.617021 (-4700 1350);
PAINT SKYBLUE (-4700 1350);
FORCEPROP 1 LAST VOLTAGE 25V
J 2
(-4700 1550);
DISPLAY 0.617021 (-4700 1550);
PAINT SKYBLUE (-4700 1550);
FORCEPROP 1 LAST MATERIAL X7R
J 2
(-4700 1450);
DISPLAY 0.617021 (-4700 1450);
PAINT SKYBLUE (-4700 1450);
FORCEPROP 2 LAST CDS_LOCATION C9L7
J 2
(-4700 1650);
DISPLAY 0.617021 (-4700 1650);
PAINT AQUA (-4700 1650);
DISPLAY INVISIBLE (-4700 1650);
FORCEPROP 2 LAST BOM_COST MEM
J 0
(-4650 1550);
PAINT ORANGE (-4650 1550);
DISPLAY INVISIBLE (-4650 1550);
FORCEPROP 2 LAST CDS_LIB dev_discrete
J 0
(-4650 1550);
PAINT ORANGE (-4650 1550);
DISPLAY INVISIBLE (-4650 1550);
FORCEPROP 2 LAST CDS_SEC 1
J 2
(-4700 1750);
PAINT MONO (-4700 1750);
DISPLAY INVISIBLE (-4700 1750);
FORCEPROP 2 LAST $SEC 1
J 0
(-4700 1750);
PAINT MONO (-4700 1750);
DISPLAY INVISIBLE (-4700 1750);
FORCEPROP 1 LAST PATH I181
J 2
(-4700 1700);
DISPLAY 0.978723 (-4700 1700);
PAINT WHITE (-4700 1700);
DISPLAY INVISIBLE (-4700 1700);
FORCEPROP 2 LAST ROOM DDR4_CH_L
J 0
(-4650 1550);
PAINT ORANGE (-4650 1550);
DISPLAY INVISIBLE (-4650 1550);
FORCEPROP 1 LASTPIN (-4650 1650) $PN 1
J 2
(-4660 1630);
DISPLAY 0.787234 (-4660 1630);
PAINT ORANGE (-4660 1630);
DISPLAY INVISIBLE (-4660 1630);
FORCEPROP 1 LASTPIN (-4650 1450) $PN 2
J 2
(-4660 1430);
DISPLAY 0.787234 (-4660 1430);
PAINT ORANGE (-4660 1430);
DISPLAY INVISIBLE (-4660 1430);
FORCEADD PVPP_KLM..1
(-950 3075);
FORCEPROP 3 LASTPIN (-950 3025) SIG_NAME PVPP_KLM\g
J 0
(-940 3035);
DISPLAY 0.659574 (-940 3035);
PAINT MONO (-940 3035);
DISPLAY INVISIBLE (-940 3035);
FORCEPROP 1 LAST VOLTAGE 2.5V
J 0
(-995 3032);
DISPLAY 0.340426 (-995 3032);
PAINT SKYBLUE (-995 3032);
DISPLAY INVISIBLE (-995 3032);
FORCEPROP 0 LAST BOM_COST MEM
J 0
(-950 3175);
PAINT ORANGE (-950 3175);
DISPLAY INVISIBLE (-950 3175);
FORCEPROP 2 LAST CDS_LIB mstr_symbols
J 0
(-950 3075);
PAINT ORANGE (-950 3075);
DISPLAY INVISIBLE (-950 3075);
FORCEPROP 1 LAST BODY_TYPE PLUMBING
J 0
(-995 3032);
DISPLAY 0.340426 (-995 3032);
PAINT GREEN (-995 3032);
DISPLAY INVISIBLE (-995 3032);
FORCEPROP 1 LAST PATH I182
J 0
(-900 3100);
DISPLAY 0.872340 (-900 3100);
PAINT AQUA (-900 3100);
DISPLAY INVISIBLE (-900 3100);
FORCEPROP 2 LAST ROOM DDR4_CH_D
J 0
(-950 3175);
PAINT ORANGE (-950 3175);
DISPLAY INVISIBLE (-950 3175);
FORCEPROP 1 LAST HDL_POWER PVPP_KLM
J 1
(-950 3125);
DISPLAY 0.872340 (-950 3125);
PAINT GREEN (-950 3125);
DISPLAY INVISIBLE (-950 3125);
FORCEADD PVPP_KLM..1
(-5150 2250);
FORCEPROP 3 LASTPIN (-5150 2200) SIG_NAME PVPP_KLM\g
J 0
(-5140 2210);
DISPLAY 0.659574 (-5140 2210);
PAINT MONO (-5140 2210);
DISPLAY INVISIBLE (-5140 2210);
FORCEPROP 1 LAST VOLTAGE 2.5V
J 0
(-5195 2207);
DISPLAY 0.340426 (-5195 2207);
PAINT SKYBLUE (-5195 2207);
DISPLAY INVISIBLE (-5195 2207);
FORCEPROP 0 LAST BOM_COST MEM
J 0
(-5150 2350);
PAINT ORANGE (-5150 2350);
DISPLAY INVISIBLE (-5150 2350);
FORCEPROP 2 LAST CDS_LIB mstr_symbols
J 0
(-5150 2250);
PAINT ORANGE (-5150 2250);
DISPLAY INVISIBLE (-5150 2250);
FORCEPROP 1 LAST BODY_TYPE PLUMBING
J 0
(-5195 2207);
DISPLAY 0.340426 (-5195 2207);
PAINT GREEN (-5195 2207);
DISPLAY INVISIBLE (-5195 2207);
FORCEPROP 1 LAST PATH I183
J 0
(-5100 2275);
DISPLAY 0.872340 (-5100 2275);
PAINT AQUA (-5100 2275);
DISPLAY INVISIBLE (-5100 2275);
FORCEPROP 2 LAST ROOM DDR4_CH_M
J 0
(-5150 2350);
PAINT ORANGE (-5150 2350);
DISPLAY INVISIBLE (-5150 2350);
FORCEPROP 1 LAST HDL_POWER PVPP_KLM
J 1
(-5150 2300);
DISPLAY 0.872340 (-5150 2300);
PAINT GREEN (-5150 2300);
DISPLAY INVISIBLE (-5150 2300);
FORCEADD OFFPAGE..1
(-3900 1450);
FORCEPROP 2 LAST $XR5 88 
J 0
(-4571 1450);
DISPLAY 0.638298 (-4571 1450);
PAINT MONO (-4571 1450);
FORCEPROP 2 LAST $XR4 87 
J 0
(-4481 1450);
DISPLAY 0.638298 (-4481 1450);
PAINT MONO (-4481 1450);
FORCEPROP 2 LAST $XR3 86 
J 0
(-4391 1450);
DISPLAY 0.638298 (-4391 1450);
PAINT MONO (-4391 1450);
FORCEPROP 2 LAST $XR2 84 
J 0
(-4301 1450);
DISPLAY 0.638298 (-4301 1450);
PAINT MONO (-4301 1450);
FORCEPROP 2 LAST $XR1 83 
J 0
(-4211 1450);
DISPLAY 0.638298 (-4211 1450);
PAINT MONO (-4211 1450);
FORCEPROP 2 LAST $XR0 89 
J 0
(-4121 1450);
DISPLAY 0.638298 (-4121 1450);
PAINT MONO (-4121 1450);
FORCEPROP 2 LAST CDS_LIB mstr_standard
J 0
(-3900 1450);
PAINT ORANGE (-3900 1450);
DISPLAY INVISIBLE (-3900 1450);
FORCEPROP 1 LAST OFFPAGE TRUE
J 0
(-3575 1325);
DISPLAY 0.936170 (-3575 1325);
PAINT GREEN (-3575 1325);
DISPLAY INVISIBLE (-3575 1325);
FORCEPROP 1 LAST COMMENT_BODY TRUE
J 0
(-3775 1350);
DISPLAY 0.936170 (-3775 1350);
PAINT GREEN (-3775 1350);
DISPLAY INVISIBLE (-3775 1350);
FORCEPROP 2 LAST PATH I184
J 0
(-3850 1525);
PAINT ORANGE (-3850 1525);
DISPLAY INVISIBLE (-3850 1525);
FORCEADD P12V_NVDIMM_KLM..1
(375 3025);
FORCEPROP 3 LASTPIN (375 2975) SIG_NAME P12V_NVDIMM_KLM\g
J 0
(385 2985);
DISPLAY 0.659574 (385 2985);
PAINT MONO (385 2985);
DISPLAY INVISIBLE (385 2985);
FORCEPROP 1 LAST VOLTAGE 12.0
J 0
(330 2982);
DISPLAY 0.340426 (330 2982);
PAINT SKYBLUE (330 2982);
DISPLAY INVISIBLE (330 2982);
FORCEPROP 2 LAST CDS_LIB mstr_symbols
J 0
(375 3025);
PAINT ORANGE (375 3025);
DISPLAY INVISIBLE (375 3025);
FORCEPROP 1 LAST BODY_TYPE PLUMBING
J 0
(330 2982);
DISPLAY 0.340426 (330 2982);
PAINT GREEN (330 2982);
DISPLAY INVISIBLE (330 2982);
FORCEPROP 1 LAST PATH I185
J 0
(425 3050);
DISPLAY 0.872340 (425 3050);
PAINT AQUA (425 3050);
DISPLAY INVISIBLE (425 3050);
FORCEPROP 1 LAST HDL_POWER P12V_NVDIMM_KLM
J 1
(375 3075);
DISPLAY 0.872340 (375 3075);
PAINT GREEN (375 3075);
DISPLAY INVISIBLE (375 3075);
FORCEADD TAP..6
R 2
(900 4500);
FORCEPROP 3 LASTPIN (850 4500) SIG_NAME M_L_DQS_DN<11>
J 0
(860 4510);
DISPLAY 0.659574 (860 4510);
PAINT MONO (860 4510);
DISPLAY INVISIBLE (860 4510);
FORCEPROP 1 LASTPIN (850 4500) BN 11
J 2
(900 4510);
DISPLAY 0.617021 (900 4510);
PAINT PINK (900 4510);
FORCEPROP 2 LAST CDS_LIB mstr_standard
J 0
(900 4500);
DISPLAY 0.787234 (900 4500);
PAINT MONO (900 4500);
DISPLAY INVISIBLE (900 4500);
FORCEPROP 1 LAST BODY_TYPE PLUMBING
J 2
(900 4450);
DISPLAY 1.234043 (900 4450);
PAINT GREEN (900 4450);
DISPLAY INVISIBLE (900 4450);
FORCEPROP 1 LAST HDL_TAP TRUE
J 2
(575 4375);
DISPLAY 1.234043 (575 4375);
PAINT GREEN (575 4375);
DISPLAY INVISIBLE (575 4375);
FORCEPROP 1 LAST PATH I19
J 2
(900 4500);
DISPLAY 0.936170 (900 4500);
PAINT GREEN (900 4500);
DISPLAY INVISIBLE (900 4500);
FORCEADD OFFPAGE..3
(1600 5150);
FORCEPROP 2 LAST $XR1 86 
J 0
(1904 5150);
DISPLAY 0.638298 (1904 5150);
PAINT MONO (1904 5150);
FORCEPROP 2 LAST $XR0 61 
J 0
(1814 5150);
DISPLAY 0.638298 (1814 5150);
PAINT MONO (1814 5150);
FORCEPROP 2 LAST CDS_LIB mstr_standard
J 0
(1600 5150);
DISPLAY 0.787234 (1600 5150);
PAINT MONO (1600 5150);
DISPLAY INVISIBLE (1600 5150);
FORCEPROP 1 LAST OFFPAGE TRUE
J 0
(1925 5025);
DISPLAY 0.936170 (1925 5025);
PAINT GREEN (1925 5025);
DISPLAY INVISIBLE (1925 5025);
FORCEPROP 1 LAST COMMENT_BODY TRUE
J 0
(1550 5050);
DISPLAY 0.936170 (1550 5050);
PAINT GREEN (1550 5050);
DISPLAY INVISIBLE (1550 5050);
FORCEPROP 2 LAST PATH I2
J 0
(1800 5225);
DISPLAY 0.787234 (1800 5225);
PAINT MONO (1800 5225);
DISPLAY INVISIBLE (1800 5225);
FORCEADD TAP..6
R 2
(900 4400);
FORCEPROP 3 LASTPIN (850 4400) SIG_NAME M_L_DQS_DN<10>
J 0
(860 4410);
DISPLAY 0.659574 (860 4410);
PAINT MONO (860 4410);
DISPLAY INVISIBLE (860 4410);
FORCEPROP 1 LASTPIN (850 4400) BN 10
J 2
(900 4410);
DISPLAY 0.617021 (900 4410);
PAINT PINK (900 4410);
FORCEPROP 2 LAST CDS_LIB mstr_standard
J 0
(900 4400);
DISPLAY 0.787234 (900 4400);
PAINT MONO (900 4400);
DISPLAY INVISIBLE (900 4400);
FORCEPROP 1 LAST BODY_TYPE PLUMBING
J 2
(900 4350);
DISPLAY 1.234043 (900 4350);
PAINT GREEN (900 4350);
DISPLAY INVISIBLE (900 4350);
FORCEPROP 1 LAST HDL_TAP TRUE
J 2
(575 4275);
DISPLAY 1.234043 (575 4275);
PAINT GREEN (575 4275);
DISPLAY INVISIBLE (575 4275);
FORCEPROP 1 LAST PATH I20
J 2
(900 4400);
DISPLAY 0.936170 (900 4400);
PAINT GREEN (900 4400);
DISPLAY INVISIBLE (900 4400);
FORCEADD TAP..6
R 2
(900 4300);
FORCEPROP 3 LASTPIN (850 4300) SIG_NAME M_L_DQS_DN<9>
J 0
(860 4310);
DISPLAY 0.659574 (860 4310);
PAINT MONO (860 4310);
DISPLAY INVISIBLE (860 4310);
FORCEPROP 1 LASTPIN (850 4300) BN 9
J 2
(900 4310);
DISPLAY 0.617021 (900 4310);
PAINT PINK (900 4310);
FORCEPROP 2 LAST CDS_LIB mstr_standard
J 0
(900 4300);
DISPLAY 0.787234 (900 4300);
PAINT MONO (900 4300);
DISPLAY INVISIBLE (900 4300);
FORCEPROP 1 LAST BODY_TYPE PLUMBING
J 2
(900 4250);
DISPLAY 1.234043 (900 4250);
PAINT GREEN (900 4250);
DISPLAY INVISIBLE (900 4250);
FORCEPROP 1 LAST HDL_TAP TRUE
J 2
(575 4175);
DISPLAY 1.234043 (575 4175);
PAINT GREEN (575 4175);
DISPLAY INVISIBLE (575 4175);
FORCEPROP 1 LAST PATH I21
J 2
(900 4300);
DISPLAY 0.936170 (900 4300);
PAINT GREEN (900 4300);
DISPLAY INVISIBLE (900 4300);
FORCEADD TAP..6
R 2
(900 4200);
FORCEPROP 3 LASTPIN (850 4200) SIG_NAME M_L_DQS_DN<8>
J 0
(860 4210);
DISPLAY 0.659574 (860 4210);
PAINT MONO (860 4210);
DISPLAY INVISIBLE (860 4210);
FORCEPROP 1 LASTPIN (850 4200) BN 8
J 2
(900 4210);
DISPLAY 0.617021 (900 4210);
PAINT PINK (900 4210);
FORCEPROP 2 LAST CDS_LIB mstr_standard
J 0
(900 4200);
DISPLAY 0.787234 (900 4200);
PAINT MONO (900 4200);
DISPLAY INVISIBLE (900 4200);
FORCEPROP 1 LAST BODY_TYPE PLUMBING
J 2
(900 4150);
DISPLAY 1.234043 (900 4150);
PAINT GREEN (900 4150);
DISPLAY INVISIBLE (900 4150);
FORCEPROP 1 LAST HDL_TAP TRUE
J 2
(575 4075);
DISPLAY 1.234043 (575 4075);
PAINT GREEN (575 4075);
DISPLAY INVISIBLE (575 4075);
FORCEPROP 1 LAST PATH I22
J 2
(900 4200);
DISPLAY 0.936170 (900 4200);
PAINT GREEN (900 4200);
DISPLAY INVISIBLE (900 4200);
FORCEADD TAP..6
R 2
(900 4100);
FORCEPROP 3 LASTPIN (850 4100) SIG_NAME M_L_DQS_DN<7>
J 0
(860 4110);
DISPLAY 0.659574 (860 4110);
PAINT MONO (860 4110);
DISPLAY INVISIBLE (860 4110);
FORCEPROP 1 LASTPIN (850 4100) BN 7
J 2
(900 4110);
DISPLAY 0.617021 (900 4110);
PAINT PINK (900 4110);
FORCEPROP 2 LAST CDS_LIB mstr_standard
J 0
(900 4100);
DISPLAY 0.787234 (900 4100);
PAINT MONO (900 4100);
DISPLAY INVISIBLE (900 4100);
FORCEPROP 1 LAST BODY_TYPE PLUMBING
J 2
(900 4050);
DISPLAY 1.234043 (900 4050);
PAINT GREEN (900 4050);
DISPLAY INVISIBLE (900 4050);
FORCEPROP 1 LAST HDL_TAP TRUE
J 2
(575 3975);
DISPLAY 1.234043 (575 3975);
PAINT GREEN (575 3975);
DISPLAY INVISIBLE (575 3975);
FORCEPROP 1 LAST PATH I23
J 2
(900 4100);
DISPLAY 0.936170 (900 4100);
PAINT GREEN (900 4100);
DISPLAY INVISIBLE (900 4100);
FORCEADD TAP..6
R 2
(700 4450);
FORCEPROP 3 LASTPIN (650 4450) SIG_NAME M_L_DQS_DP<10>
J 0
(660 4460);
DISPLAY 0.659574 (660 4460);
PAINT MONO (660 4460);
DISPLAY INVISIBLE (660 4460);
FORCEPROP 1 LASTPIN (650 4450) BN 10
J 2
(700 4460);
DISPLAY 0.617021 (700 4460);
PAINT PINK (700 4460);
FORCEPROP 2 LAST CDS_LIB mstr_standard
J 0
(700 4450);
DISPLAY 0.787234 (700 4450);
PAINT MONO (700 4450);
DISPLAY INVISIBLE (700 4450);
FORCEPROP 1 LAST BODY_TYPE PLUMBING
J 2
(700 4400);
DISPLAY 1.234043 (700 4400);
PAINT GREEN (700 4400);
DISPLAY INVISIBLE (700 4400);
FORCEPROP 1 LAST HDL_TAP TRUE
J 2
(375 4325);
DISPLAY 1.234043 (375 4325);
PAINT GREEN (375 4325);
DISPLAY INVISIBLE (375 4325);
FORCEPROP 1 LAST PATH I24
J 2
(700 4450);
DISPLAY 0.936170 (700 4450);
PAINT GREEN (700 4450);
DISPLAY INVISIBLE (700 4450);
FORCEADD TAP..6
R 2
(700 4350);
FORCEPROP 3 LASTPIN (650 4350) SIG_NAME M_L_DQS_DP<9>
J 0
(660 4360);
DISPLAY 0.659574 (660 4360);
PAINT MONO (660 4360);
DISPLAY INVISIBLE (660 4360);
FORCEPROP 1 LASTPIN (650 4350) BN 9
J 2
(700 4360);
DISPLAY 0.617021 (700 4360);
PAINT PINK (700 4360);
FORCEPROP 2 LAST CDS_LIB mstr_standard
J 0
(700 4350);
DISPLAY 0.787234 (700 4350);
PAINT MONO (700 4350);
DISPLAY INVISIBLE (700 4350);
FORCEPROP 1 LAST BODY_TYPE PLUMBING
J 2
(700 4300);
DISPLAY 1.234043 (700 4300);
PAINT GREEN (700 4300);
DISPLAY INVISIBLE (700 4300);
FORCEPROP 1 LAST HDL_TAP TRUE
J 2
(375 4225);
DISPLAY 1.234043 (375 4225);
PAINT GREEN (375 4225);
DISPLAY INVISIBLE (375 4225);
FORCEPROP 1 LAST PATH I25
J 2
(700 4350);
DISPLAY 0.936170 (700 4350);
PAINT GREEN (700 4350);
DISPLAY INVISIBLE (700 4350);
FORCEADD TAP..6
R 2
(700 4050);
FORCEPROP 3 LASTPIN (650 4050) SIG_NAME M_L_DQS_DP<6>
J 0
(660 4060);
DISPLAY 0.659574 (660 4060);
PAINT MONO (660 4060);
DISPLAY INVISIBLE (660 4060);
FORCEPROP 1 LASTPIN (650 4050) BN 6
J 2
(700 4060);
DISPLAY 0.617021 (700 4060);
PAINT PINK (700 4060);
FORCEPROP 2 LAST CDS_LIB mstr_standard
J 0
(700 4050);
DISPLAY 0.787234 (700 4050);
PAINT MONO (700 4050);
DISPLAY INVISIBLE (700 4050);
FORCEPROP 1 LAST BODY_TYPE PLUMBING
J 2
(700 4000);
DISPLAY 1.234043 (700 4000);
PAINT GREEN (700 4000);
DISPLAY INVISIBLE (700 4000);
FORCEPROP 1 LAST HDL_TAP TRUE
J 2
(375 3925);
DISPLAY 1.234043 (375 3925);
PAINT GREEN (375 3925);
DISPLAY INVISIBLE (375 3925);
FORCEPROP 1 LAST PATH I26
J 2
(700 4050);
DISPLAY 0.936170 (700 4050);
PAINT GREEN (700 4050);
DISPLAY INVISIBLE (700 4050);
FORCEADD TAP..6
R 2
(700 4150);
FORCEPROP 3 LASTPIN (650 4150) SIG_NAME M_L_DQS_DP<7>
J 0
(660 4160);
DISPLAY 0.659574 (660 4160);
PAINT MONO (660 4160);
DISPLAY INVISIBLE (660 4160);
FORCEPROP 1 LASTPIN (650 4150) BN 7
J 2
(700 4160);
DISPLAY 0.617021 (700 4160);
PAINT PINK (700 4160);
FORCEPROP 2 LAST CDS_LIB mstr_standard
J 0
(700 4150);
DISPLAY 0.787234 (700 4150);
PAINT MONO (700 4150);
DISPLAY INVISIBLE (700 4150);
FORCEPROP 1 LAST BODY_TYPE PLUMBING
J 2
(700 4100);
DISPLAY 1.234043 (700 4100);
PAINT GREEN (700 4100);
DISPLAY INVISIBLE (700 4100);
FORCEPROP 1 LAST HDL_TAP TRUE
J 2
(375 4025);
DISPLAY 1.234043 (375 4025);
PAINT GREEN (375 4025);
DISPLAY INVISIBLE (375 4025);
FORCEPROP 1 LAST PATH I27
J 2
(700 4150);
DISPLAY 0.936170 (700 4150);
PAINT GREEN (700 4150);
DISPLAY INVISIBLE (700 4150);
FORCEADD TAP..6
R 2
(700 4250);
FORCEPROP 3 LASTPIN (650 4250) SIG_NAME M_L_DQS_DP<8>
J 0
(660 4260);
DISPLAY 0.659574 (660 4260);
PAINT MONO (660 4260);
DISPLAY INVISIBLE (660 4260);
FORCEPROP 1 LASTPIN (650 4250) BN 8
J 2
(700 4260);
DISPLAY 0.617021 (700 4260);
PAINT PINK (700 4260);
FORCEPROP 2 LAST CDS_LIB mstr_standard
J 0
(700 4250);
DISPLAY 0.787234 (700 4250);
PAINT MONO (700 4250);
DISPLAY INVISIBLE (700 4250);
FORCEPROP 1 LAST BODY_TYPE PLUMBING
J 2
(700 4200);
DISPLAY 1.234043 (700 4200);
PAINT GREEN (700 4200);
DISPLAY INVISIBLE (700 4200);
FORCEPROP 1 LAST HDL_TAP TRUE
J 2
(375 4125);
DISPLAY 1.234043 (375 4125);
PAINT GREEN (375 4125);
DISPLAY INVISIBLE (375 4125);
FORCEPROP 1 LAST PATH I28
J 2
(700 4250);
DISPLAY 0.936170 (700 4250);
PAINT GREEN (700 4250);
DISPLAY INVISIBLE (700 4250);
FORCEADD TAP..6
R 2
(900 4000);
FORCEPROP 3 LASTPIN (850 4000) SIG_NAME M_L_DQS_DN<6>
J 0
(860 4010);
DISPLAY 0.659574 (860 4010);
PAINT MONO (860 4010);
DISPLAY INVISIBLE (860 4010);
FORCEPROP 1 LASTPIN (850 4000) BN 6
J 2
(900 4010);
DISPLAY 0.617021 (900 4010);
PAINT PINK (900 4010);
FORCEPROP 2 LAST CDS_LIB mstr_standard
J 0
(900 4000);
DISPLAY 0.787234 (900 4000);
PAINT MONO (900 4000);
DISPLAY INVISIBLE (900 4000);
FORCEPROP 1 LAST BODY_TYPE PLUMBING
J 2
(900 3950);
DISPLAY 1.234043 (900 3950);
PAINT GREEN (900 3950);
DISPLAY INVISIBLE (900 3950);
FORCEPROP 1 LAST HDL_TAP TRUE
J 2
(575 3875);
DISPLAY 1.234043 (575 3875);
PAINT GREEN (575 3875);
DISPLAY INVISIBLE (575 3875);
FORCEPROP 1 LAST PATH I29
J 2
(900 4000);
DISPLAY 0.936170 (900 4000);
PAINT GREEN (900 4000);
DISPLAY INVISIBLE (900 4000);
FORCEADD TAP..6
R 2
(900 5100);
FORCEPROP 3 LASTPIN (850 5100) SIG_NAME M_L_DQS_DN<17>
J 0
(860 5110);
DISPLAY 0.659574 (860 5110);
PAINT MONO (860 5110);
DISPLAY INVISIBLE (860 5110);
FORCEPROP 1 LASTPIN (850 5100) BN 17
J 2
(900 5110);
DISPLAY 0.617021 (900 5110);
PAINT PINK (900 5110);
FORCEPROP 2 LAST CDS_LIB mstr_standard
J 2
(900 5100);
DISPLAY 0.787234 (900 5100);
PAINT MONO (900 5100);
DISPLAY INVISIBLE (900 5100);
FORCEPROP 1 LAST BODY_TYPE PLUMBING
J 2
(900 5050);
DISPLAY 1.234043 (900 5050);
PAINT GREEN (900 5050);
DISPLAY INVISIBLE (900 5050);
FORCEPROP 1 LAST HDL_TAP TRUE
J 2
(575 4975);
DISPLAY 1.234043 (575 4975);
PAINT GREEN (575 4975);
DISPLAY INVISIBLE (575 4975);
FORCEPROP 1 LAST PATH I3
J 2
(900 5100);
DISPLAY 0.936170 (900 5100);
PAINT GREEN (900 5100);
DISPLAY INVISIBLE (900 5100);
FORCEADD TAP..6
R 2
(900 3900);
FORCEPROP 3 LASTPIN (850 3900) SIG_NAME M_L_DQS_DN<5>
J 0
(860 3910);
DISPLAY 0.659574 (860 3910);
PAINT MONO (860 3910);
DISPLAY INVISIBLE (860 3910);
FORCEPROP 1 LASTPIN (850 3900) BN 5
J 2
(900 3910);
DISPLAY 0.617021 (900 3910);
PAINT PINK (900 3910);
FORCEPROP 2 LAST CDS_LIB mstr_standard
J 0
(900 3900);
DISPLAY 0.787234 (900 3900);
PAINT MONO (900 3900);
DISPLAY INVISIBLE (900 3900);
FORCEPROP 1 LAST BODY_TYPE PLUMBING
J 2
(900 3850);
DISPLAY 1.234043 (900 3850);
PAINT GREEN (900 3850);
DISPLAY INVISIBLE (900 3850);
FORCEPROP 1 LAST HDL_TAP TRUE
J 2
(575 3775);
DISPLAY 1.234043 (575 3775);
PAINT GREEN (575 3775);
DISPLAY INVISIBLE (575 3775);
FORCEPROP 1 LAST PATH I30
J 2
(900 3900);
DISPLAY 0.936170 (900 3900);
PAINT GREEN (900 3900);
DISPLAY INVISIBLE (900 3900);
FORCEADD TAP..6
R 2
(900 3800);
FORCEPROP 3 LASTPIN (850 3800) SIG_NAME M_L_DQS_DN<4>
J 0
(860 3810);
DISPLAY 0.659574 (860 3810);
PAINT MONO (860 3810);
DISPLAY INVISIBLE (860 3810);
FORCEPROP 1 LASTPIN (850 3800) BN 4
J 2
(900 3810);
DISPLAY 0.617021 (900 3810);
PAINT PINK (900 3810);
FORCEPROP 2 LAST CDS_LIB mstr_standard
J 0
(900 3800);
DISPLAY 0.787234 (900 3800);
PAINT MONO (900 3800);
DISPLAY INVISIBLE (900 3800);
FORCEPROP 1 LAST BODY_TYPE PLUMBING
J 2
(900 3750);
DISPLAY 1.234043 (900 3750);
PAINT GREEN (900 3750);
DISPLAY INVISIBLE (900 3750);
FORCEPROP 1 LAST HDL_TAP TRUE
J 2
(575 3675);
DISPLAY 1.234043 (575 3675);
PAINT GREEN (575 3675);
DISPLAY INVISIBLE (575 3675);
FORCEPROP 1 LAST PATH I31
J 2
(900 3800);
DISPLAY 0.936170 (900 3800);
PAINT GREEN (900 3800);
DISPLAY INVISIBLE (900 3800);
FORCEADD TAP..6
R 2
(900 3700);
FORCEPROP 3 LASTPIN (850 3700) SIG_NAME M_L_DQS_DN<3>
J 0
(860 3710);
DISPLAY 0.659574 (860 3710);
PAINT MONO (860 3710);
DISPLAY INVISIBLE (860 3710);
FORCEPROP 1 LASTPIN (850 3700) BN 3
J 2
(900 3710);
DISPLAY 0.617021 (900 3710);
PAINT PINK (900 3710);
FORCEPROP 2 LAST CDS_LIB mstr_standard
J 0
(900 3700);
DISPLAY 0.787234 (900 3700);
PAINT MONO (900 3700);
DISPLAY INVISIBLE (900 3700);
FORCEPROP 1 LAST BODY_TYPE PLUMBING
J 2
(900 3650);
DISPLAY 1.234043 (900 3650);
PAINT GREEN (900 3650);
DISPLAY INVISIBLE (900 3650);
FORCEPROP 1 LAST HDL_TAP TRUE
J 2
(575 3575);
DISPLAY 1.234043 (575 3575);
PAINT GREEN (575 3575);
DISPLAY INVISIBLE (575 3575);
FORCEPROP 1 LAST PATH I32
J 2
(900 3700);
DISPLAY 0.936170 (900 3700);
PAINT GREEN (900 3700);
DISPLAY INVISIBLE (900 3700);
FORCEADD TAP..6
R 2
(900 3600);
FORCEPROP 3 LASTPIN (850 3600) SIG_NAME M_L_DQS_DN<2>
J 0
(860 3610);
DISPLAY 0.659574 (860 3610);
PAINT MONO (860 3610);
DISPLAY INVISIBLE (860 3610);
FORCEPROP 1 LASTPIN (850 3600) BN 2
J 2
(900 3610);
DISPLAY 0.617021 (900 3610);
PAINT PINK (900 3610);
FORCEPROP 2 LAST CDS_LIB mstr_standard
J 0
(900 3600);
DISPLAY 0.787234 (900 3600);
PAINT MONO (900 3600);
DISPLAY INVISIBLE (900 3600);
FORCEPROP 1 LAST BODY_TYPE PLUMBING
J 2
(900 3550);
DISPLAY 1.234043 (900 3550);
PAINT GREEN (900 3550);
DISPLAY INVISIBLE (900 3550);
FORCEPROP 1 LAST HDL_TAP TRUE
J 2
(575 3475);
DISPLAY 1.234043 (575 3475);
PAINT GREEN (575 3475);
DISPLAY INVISIBLE (575 3475);
FORCEPROP 1 LAST PATH I33
J 2
(900 3600);
DISPLAY 0.936170 (900 3600);
PAINT GREEN (900 3600);
DISPLAY INVISIBLE (900 3600);
FORCEADD TAP..6
R 2
(700 3950);
FORCEPROP 3 LASTPIN (650 3950) SIG_NAME M_L_DQS_DP<5>
J 0
(660 3960);
DISPLAY 0.659574 (660 3960);
PAINT MONO (660 3960);
DISPLAY INVISIBLE (660 3960);
FORCEPROP 1 LASTPIN (650 3950) BN 5
J 2
(700 3960);
DISPLAY 0.617021 (700 3960);
PAINT PINK (700 3960);
FORCEPROP 2 LAST CDS_LIB mstr_standard
J 0
(700 3950);
DISPLAY 0.787234 (700 3950);
PAINT MONO (700 3950);
DISPLAY INVISIBLE (700 3950);
FORCEPROP 1 LAST BODY_TYPE PLUMBING
J 2
(700 3900);
DISPLAY 1.234043 (700 3900);
PAINT GREEN (700 3900);
DISPLAY INVISIBLE (700 3900);
FORCEPROP 1 LAST HDL_TAP TRUE
J 2
(375 3825);
DISPLAY 1.234043 (375 3825);
PAINT GREEN (375 3825);
DISPLAY INVISIBLE (375 3825);
FORCEPROP 1 LAST PATH I34
J 2
(700 3950);
DISPLAY 0.936170 (700 3950);
PAINT GREEN (700 3950);
DISPLAY INVISIBLE (700 3950);
FORCEADD TAP..6
R 2
(700 3850);
FORCEPROP 3 LASTPIN (650 3850) SIG_NAME M_L_DQS_DP<4>
J 0
(660 3860);
DISPLAY 0.659574 (660 3860);
PAINT MONO (660 3860);
DISPLAY INVISIBLE (660 3860);
FORCEPROP 1 LASTPIN (650 3850) BN 4
J 2
(700 3860);
DISPLAY 0.617021 (700 3860);
PAINT PINK (700 3860);
FORCEPROP 2 LAST CDS_LIB mstr_standard
J 0
(700 3850);
DISPLAY 0.787234 (700 3850);
PAINT MONO (700 3850);
DISPLAY INVISIBLE (700 3850);
FORCEPROP 1 LAST BODY_TYPE PLUMBING
J 2
(700 3800);
DISPLAY 1.234043 (700 3800);
PAINT GREEN (700 3800);
DISPLAY INVISIBLE (700 3800);
FORCEPROP 1 LAST HDL_TAP TRUE
J 2
(375 3725);
DISPLAY 1.234043 (375 3725);
PAINT GREEN (375 3725);
DISPLAY INVISIBLE (375 3725);
FORCEPROP 1 LAST PATH I35
J 2
(700 3850);
DISPLAY 0.936170 (700 3850);
PAINT GREEN (700 3850);
DISPLAY INVISIBLE (700 3850);
FORCEADD TAP..6
R 2
(700 3650);
FORCEPROP 3 LASTPIN (650 3650) SIG_NAME M_L_DQS_DP<2>
J 0
(660 3660);
DISPLAY 0.659574 (660 3660);
PAINT MONO (660 3660);
DISPLAY INVISIBLE (660 3660);
FORCEPROP 1 LASTPIN (650 3650) BN 2
J 2
(700 3660);
DISPLAY 0.617021 (700 3660);
PAINT PINK (700 3660);
FORCEPROP 2 LAST CDS_LIB mstr_standard
J 0
(700 3650);
DISPLAY 0.787234 (700 3650);
PAINT MONO (700 3650);
DISPLAY INVISIBLE (700 3650);
FORCEPROP 1 LAST BODY_TYPE PLUMBING
J 2
(700 3600);
DISPLAY 1.234043 (700 3600);
PAINT GREEN (700 3600);
DISPLAY INVISIBLE (700 3600);
FORCEPROP 1 LAST HDL_TAP TRUE
J 2
(375 3525);
DISPLAY 1.234043 (375 3525);
PAINT GREEN (375 3525);
DISPLAY INVISIBLE (375 3525);
FORCEPROP 1 LAST PATH I36
J 2
(700 3650);
DISPLAY 0.936170 (700 3650);
PAINT GREEN (700 3650);
DISPLAY INVISIBLE (700 3650);
FORCEADD TAP..6
R 2
(700 3550);
FORCEPROP 3 LASTPIN (650 3550) SIG_NAME M_L_DQS_DP<1>
J 0
(660 3560);
DISPLAY 0.659574 (660 3560);
PAINT MONO (660 3560);
DISPLAY INVISIBLE (660 3560);
FORCEPROP 1 LASTPIN (650 3550) BN 1
J 2
(700 3560);
DISPLAY 0.617021 (700 3560);
PAINT PINK (700 3560);
FORCEPROP 2 LAST CDS_LIB mstr_standard
J 0
(700 3550);
DISPLAY 0.787234 (700 3550);
PAINT MONO (700 3550);
DISPLAY INVISIBLE (700 3550);
FORCEPROP 1 LAST BODY_TYPE PLUMBING
J 2
(700 3500);
DISPLAY 1.234043 (700 3500);
PAINT GREEN (700 3500);
DISPLAY INVISIBLE (700 3500);
FORCEPROP 1 LAST HDL_TAP TRUE
J 2
(375 3425);
DISPLAY 1.234043 (375 3425);
PAINT GREEN (375 3425);
DISPLAY INVISIBLE (375 3425);
FORCEPROP 1 LAST PATH I37
J 2
(700 3550);
DISPLAY 0.936170 (700 3550);
PAINT GREEN (700 3550);
DISPLAY INVISIBLE (700 3550);
FORCEADD TAP..6
R 2
(700 3750);
FORCEPROP 3 LASTPIN (650 3750) SIG_NAME M_L_DQS_DP<3>
J 0
(660 3760);
DISPLAY 0.659574 (660 3760);
PAINT MONO (660 3760);
DISPLAY INVISIBLE (660 3760);
FORCEPROP 1 LASTPIN (650 3750) BN 3
J 2
(700 3760);
DISPLAY 0.617021 (700 3760);
PAINT PINK (700 3760);
FORCEPROP 2 LAST CDS_LIB mstr_standard
J 0
(700 3750);
DISPLAY 0.787234 (700 3750);
PAINT MONO (700 3750);
DISPLAY INVISIBLE (700 3750);
FORCEPROP 1 LAST BODY_TYPE PLUMBING
J 2
(700 3700);
DISPLAY 1.234043 (700 3700);
PAINT GREEN (700 3700);
DISPLAY INVISIBLE (700 3700);
FORCEPROP 1 LAST HDL_TAP TRUE
J 2
(375 3625);
DISPLAY 1.234043 (375 3625);
PAINT GREEN (375 3625);
DISPLAY INVISIBLE (375 3625);
FORCEPROP 1 LAST PATH I38
J 2
(700 3750);
DISPLAY 0.936170 (700 3750);
PAINT GREEN (700 3750);
DISPLAY INVISIBLE (700 3750);
FORCEADD TAP..6
R 2
(900 3400);
FORCEPROP 3 LASTPIN (850 3400) SIG_NAME M_L_DQS_DN<0>
J 0
(860 3410);
DISPLAY 0.659574 (860 3410);
PAINT MONO (860 3410);
DISPLAY INVISIBLE (860 3410);
FORCEPROP 1 LASTPIN (850 3400) BN 0
J 2
(900 3410);
DISPLAY 0.617021 (900 3410);
PAINT PINK (900 3410);
FORCEPROP 2 LAST CDS_LIB mstr_standard
J 0
(900 3400);
DISPLAY 0.787234 (900 3400);
PAINT MONO (900 3400);
DISPLAY INVISIBLE (900 3400);
FORCEPROP 1 LAST BODY_TYPE PLUMBING
J 2
(900 3350);
DISPLAY 1.234043 (900 3350);
PAINT GREEN (900 3350);
DISPLAY INVISIBLE (900 3350);
FORCEPROP 1 LAST HDL_TAP TRUE
J 2
(575 3275);
DISPLAY 1.234043 (575 3275);
PAINT GREEN (575 3275);
DISPLAY INVISIBLE (575 3275);
FORCEPROP 1 LAST PATH I39
J 2
(900 3400);
DISPLAY 0.936170 (900 3400);
PAINT GREEN (900 3400);
DISPLAY INVISIBLE (900 3400);
FORCEADD TAP..6
R 2
(700 5150);
FORCEPROP 3 LASTPIN (650 5150) SIG_NAME M_L_DQS_DP<17>
J 0
(660 5160);
DISPLAY 0.659574 (660 5160);
PAINT MONO (660 5160);
DISPLAY INVISIBLE (660 5160);
FORCEPROP 1 LASTPIN (650 5150) BN 17
J 2
(700 5160);
DISPLAY 0.617021 (700 5160);
PAINT PINK (700 5160);
FORCEPROP 2 LAST CDS_LIB mstr_standard
J 2
(700 5150);
DISPLAY 0.787234 (700 5150);
PAINT MONO (700 5150);
DISPLAY INVISIBLE (700 5150);
FORCEPROP 1 LAST BODY_TYPE PLUMBING
J 2
(700 5100);
DISPLAY 1.234043 (700 5100);
PAINT GREEN (700 5100);
DISPLAY INVISIBLE (700 5100);
FORCEPROP 1 LAST HDL_TAP TRUE
J 2
(375 5025);
DISPLAY 1.234043 (375 5025);
PAINT GREEN (375 5025);
DISPLAY INVISIBLE (375 5025);
FORCEPROP 1 LAST PATH I4
J 2
(700 5150);
DISPLAY 0.936170 (700 5150);
PAINT GREEN (700 5150);
DISPLAY INVISIBLE (700 5150);
FORCEADD TAP..6
R 2
(900 3500);
FORCEPROP 3 LASTPIN (850 3500) SIG_NAME M_L_DQS_DN<1>
J 0
(860 3510);
DISPLAY 0.659574 (860 3510);
PAINT MONO (860 3510);
DISPLAY INVISIBLE (860 3510);
FORCEPROP 1 LASTPIN (850 3500) BN 1
J 2
(900 3510);
DISPLAY 0.617021 (900 3510);
PAINT PINK (900 3510);
FORCEPROP 2 LAST CDS_LIB mstr_standard
J 0
(900 3500);
DISPLAY 0.787234 (900 3500);
PAINT MONO (900 3500);
DISPLAY INVISIBLE (900 3500);
FORCEPROP 1 LAST BODY_TYPE PLUMBING
J 2
(900 3450);
DISPLAY 1.234043 (900 3450);
PAINT GREEN (900 3450);
DISPLAY INVISIBLE (900 3450);
FORCEPROP 1 LAST HDL_TAP TRUE
J 2
(575 3375);
DISPLAY 1.234043 (575 3375);
PAINT GREEN (575 3375);
DISPLAY INVISIBLE (575 3375);
FORCEPROP 1 LAST PATH I40
J 2
(900 3500);
DISPLAY 0.936170 (900 3500);
PAINT GREEN (900 3500);
DISPLAY INVISIBLE (900 3500);
FORCEADD TAP..6
R 2
(700 3450);
FORCEPROP 3 LASTPIN (650 3450) SIG_NAME M_L_DQS_DP<0>
J 0
(660 3460);
DISPLAY 0.659574 (660 3460);
PAINT MONO (660 3460);
DISPLAY INVISIBLE (660 3460);
FORCEPROP 1 LASTPIN (650 3450) BN 0
J 2
(700 3460);
DISPLAY 0.617021 (700 3460);
PAINT PINK (700 3460);
FORCEPROP 2 LAST CDS_LIB mstr_standard
J 0
(700 3450);
DISPLAY 0.787234 (700 3450);
PAINT MONO (700 3450);
DISPLAY INVISIBLE (700 3450);
FORCEPROP 1 LAST BODY_TYPE PLUMBING
J 2
(700 3400);
DISPLAY 1.234043 (700 3400);
PAINT GREEN (700 3400);
DISPLAY INVISIBLE (700 3400);
FORCEPROP 1 LAST HDL_TAP TRUE
J 2
(375 3325);
DISPLAY 1.234043 (375 3325);
PAINT GREEN (375 3325);
DISPLAY INVISIBLE (375 3325);
FORCEPROP 1 LAST PATH I41
J 2
(700 3450);
DISPLAY 0.936170 (700 3450);
PAINT GREEN (700 3450);
DISPLAY INVISIBLE (700 3450);
FORCEADD SCONN288_H44441004..3
(1800 2400);
FORCEPROP 2 LASTPIN (1300 2050) $PN 103
J 2
(1290 2060);
DISPLAY 0.617021 (1290 2060);
PAINT ORANGE (1290 2060);
FORCEPROP 2 LASTPIN (1300 1900) $PN 109
J 2
(1290 1910);
DISPLAY 0.617021 (1290 1910);
PAINT ORANGE (1290 1910);
FORCEPROP 2 LASTPIN (1300 1850) $PN 112
J 2
(1290 1860);
DISPLAY 0.617021 (1290 1860);
PAINT ORANGE (1290 1860);
FORCEPROP 1 LAST PART_NUMBER H44441-004
J 0
(1350 1050);
DISPLAY 0.617021 (1350 1050);
PAINT BLUE (1350 1050);
FORCEPROP 2 LASTPIN (2300 1250) $PN 283
J 0
(2310 1260);
DISPLAY 0.617021 (2310 1260);
PAINT ORANGE (2310 1260);
FORCEPROP 1 LAST LOCATION J1A2
J 0
(1350 3800);
DISPLAY 0.617021 (1350 3800);
PAINT AQUA (1350 3800);
FORCEPROP 1 LAST MATERIAL SCONN
J 0
(1350 3750);
DISPLAY 0.617021 (1350 3750);
PAINT SKYBLUE (1350 3750);
FORCEPROP 2 LASTPIN (1300 3550) $PN 2
J 2
(1290 3560);
DISPLAY 0.617021 (1290 3560);
PAINT ORANGE (1290 3560);
FORCEPROP 2 LASTPIN (1300 3500) $PN 4
J 2
(1290 3510);
DISPLAY 0.617021 (1290 3510);
PAINT ORANGE (1290 3510);
FORCEPROP 2 LASTPIN (1300 3450) $PN 6
J 2
(1290 3460);
DISPLAY 0.617021 (1290 3460);
PAINT ORANGE (1290 3460);
FORCEPROP 2 LASTPIN (1300 3400) $PN 9
J 2
(1290 3410);
DISPLAY 0.617021 (1290 3410);
PAINT ORANGE (1290 3410);
FORCEPROP 2 LASTPIN (1300 3350) $PN 11
J 2
(1290 3360);
DISPLAY 0.617021 (1290 3360);
PAINT ORANGE (1290 3360);
FORCEPROP 2 LASTPIN (1300 3300) $PN 13
J 2
(1290 3310);
DISPLAY 0.617021 (1290 3310);
PAINT ORANGE (1290 3310);
FORCEPROP 2 LASTPIN (1300 3250) $PN 15
J 2
(1290 3260);
DISPLAY 0.617021 (1290 3260);
PAINT ORANGE (1290 3260);
FORCEPROP 2 LASTPIN (1300 3200) $PN 17
J 2
(1290 3210);
DISPLAY 0.617021 (1290 3210);
PAINT ORANGE (1290 3210);
FORCEPROP 2 LASTPIN (1300 3150) $PN 20
J 2
(1290 3160);
DISPLAY 0.617021 (1290 3160);
PAINT ORANGE (1290 3160);
FORCEPROP 2 LASTPIN (1300 3100) $PN 22
J 2
(1290 3110);
DISPLAY 0.617021 (1290 3110);
PAINT ORANGE (1290 3110);
FORCEPROP 2 LASTPIN (1300 3050) $PN 24
J 2
(1290 3060);
DISPLAY 0.617021 (1290 3060);
PAINT ORANGE (1290 3060);
FORCEPROP 2 LASTPIN (1300 3000) $PN 26
J 2
(1290 3010);
DISPLAY 0.617021 (1290 3010);
PAINT ORANGE (1290 3010);
FORCEPROP 2 LASTPIN (1300 2950) $PN 28
J 2
(1290 2960);
DISPLAY 0.617021 (1290 2960);
PAINT ORANGE (1290 2960);
FORCEPROP 2 LASTPIN (1300 2900) $PN 31
J 2
(1290 2910);
DISPLAY 0.617021 (1290 2910);
PAINT ORANGE (1290 2910);
FORCEPROP 2 LASTPIN (1300 2850) $PN 33
J 2
(1290 2860);
DISPLAY 0.617021 (1290 2860);
PAINT ORANGE (1290 2860);
FORCEPROP 2 LASTPIN (1300 2800) $PN 35
J 2
(1290 2810);
DISPLAY 0.617021 (1290 2810);
PAINT ORANGE (1290 2810);
FORCEPROP 2 LASTPIN (1300 2750) $PN 37
J 2
(1290 2760);
DISPLAY 0.617021 (1290 2760);
PAINT ORANGE (1290 2760);
FORCEPROP 2 LASTPIN (1300 2700) $PN 39
J 2
(1290 2710);
DISPLAY 0.617021 (1290 2710);
PAINT ORANGE (1290 2710);
FORCEPROP 2 LASTPIN (1300 2650) $PN 42
J 2
(1290 2660);
DISPLAY 0.617021 (1290 2660);
PAINT ORANGE (1290 2660);
FORCEPROP 2 LASTPIN (1300 2600) $PN 44
J 2
(1290 2610);
DISPLAY 0.617021 (1290 2610);
PAINT ORANGE (1290 2610);
FORCEPROP 2 LASTPIN (1300 2550) $PN 46
J 2
(1290 2560);
DISPLAY 0.617021 (1290 2560);
PAINT ORANGE (1290 2560);
FORCEPROP 2 LASTPIN (1300 2500) $PN 48
J 2
(1290 2510);
DISPLAY 0.617021 (1290 2510);
PAINT ORANGE (1290 2510);
FORCEPROP 2 LASTPIN (1300 2450) $PN 50
J 2
(1290 2460);
DISPLAY 0.617021 (1290 2460);
PAINT ORANGE (1290 2460);
FORCEPROP 2 LASTPIN (1300 2400) $PN 53
J 2
(1290 2410);
DISPLAY 0.617021 (1290 2410);
PAINT ORANGE (1290 2410);
FORCEPROP 2 LASTPIN (1300 2350) $PN 55
J 2
(1290 2360);
DISPLAY 0.617021 (1290 2360);
PAINT ORANGE (1290 2360);
FORCEPROP 2 LASTPIN (1300 2300) $PN 57
J 2
(1290 2310);
DISPLAY 0.617021 (1290 2310);
PAINT ORANGE (1290 2310);
FORCEPROP 2 LASTPIN (1300 2250) $PN 94
J 2
(1290 2260);
DISPLAY 0.617021 (1290 2260);
PAINT ORANGE (1290 2260);
FORCEPROP 2 LASTPIN (1300 2200) $PN 96
J 2
(1290 2210);
DISPLAY 0.617021 (1290 2210);
PAINT ORANGE (1290 2210);
FORCEPROP 2 LASTPIN (1300 2150) $PN 98
J 2
(1290 2160);
DISPLAY 0.617021 (1290 2160);
PAINT ORANGE (1290 2160);
FORCEPROP 2 LASTPIN (1300 2100) $PN 101
J 2
(1290 2110);
DISPLAY 0.617021 (1290 2110);
PAINT ORANGE (1290 2110);
FORCEPROP 2 LASTPIN (1300 1800) $PN 114
J 2
(1290 1810);
DISPLAY 0.617021 (1290 1810);
PAINT ORANGE (1290 1810);
FORCEPROP 2 LASTPIN (1300 1750) $PN 116
J 2
(1290 1760);
DISPLAY 0.617021 (1290 1760);
PAINT ORANGE (1290 1760);
FORCEPROP 2 LASTPIN (1300 1700) $PN 118
J 2
(1290 1710);
DISPLAY 0.617021 (1290 1710);
PAINT ORANGE (1290 1710);
FORCEPROP 2 LASTPIN (1300 1650) $PN 120
J 2
(1290 1660);
DISPLAY 0.617021 (1290 1660);
PAINT ORANGE (1290 1660);
FORCEPROP 2 LASTPIN (1300 1600) $PN 123
J 2
(1290 1610);
DISPLAY 0.617021 (1290 1610);
PAINT ORANGE (1290 1610);
FORCEPROP 2 LASTPIN (1300 1550) $PN 125
J 2
(1290 1560);
DISPLAY 0.617021 (1290 1560);
PAINT ORANGE (1290 1560);
FORCEPROP 2 LASTPIN (1300 1450) $PN 129
J 2
(1290 1460);
DISPLAY 0.617021 (1290 1460);
PAINT ORANGE (1290 1460);
FORCEPROP 2 LASTPIN (1300 1400) $PN 131
J 2
(1290 1410);
DISPLAY 0.617021 (1290 1410);
PAINT ORANGE (1290 1410);
FORCEPROP 2 LASTPIN (1300 1350) $PN 134
J 2
(1290 1360);
DISPLAY 0.617021 (1290 1360);
PAINT ORANGE (1290 1360);
FORCEPROP 2 LASTPIN (1300 1300) $PN 136
J 2
(1290 1310);
DISPLAY 0.617021 (1290 1310);
PAINT ORANGE (1290 1310);
FORCEPROP 2 LASTPIN (1300 1250) $PN 138
J 2
(1290 1260);
DISPLAY 0.617021 (1290 1260);
PAINT ORANGE (1290 1260);
FORCEPROP 2 LASTPIN (2300 3550) $PN 147
J 0
(2310 3560);
DISPLAY 0.617021 (2310 3560);
PAINT ORANGE (2310 3560);
FORCEPROP 2 LASTPIN (2300 3500) $PN 149
J 0
(2310 3510);
DISPLAY 0.617021 (2310 3510);
PAINT ORANGE (2310 3510);
FORCEPROP 2 LASTPIN (2300 3450) $PN 151
J 0
(2310 3460);
DISPLAY 0.617021 (2310 3460);
PAINT ORANGE (2310 3460);
FORCEPROP 2 LASTPIN (2300 3400) $PN 154
J 0
(2310 3410);
DISPLAY 0.617021 (2310 3410);
PAINT ORANGE (2310 3410);
FORCEPROP 2 LASTPIN (2300 3350) $PN 156
J 0
(2310 3360);
DISPLAY 0.617021 (2310 3360);
PAINT ORANGE (2310 3360);
FORCEPROP 2 LASTPIN (2300 3300) $PN 158
J 0
(2310 3310);
DISPLAY 0.617021 (2310 3310);
PAINT ORANGE (2310 3310);
FORCEPROP 2 LASTPIN (2300 3250) $PN 160
J 0
(2310 3260);
DISPLAY 0.617021 (2310 3260);
PAINT ORANGE (2310 3260);
FORCEPROP 2 LASTPIN (2300 3200) $PN 162
J 0
(2310 3210);
DISPLAY 0.617021 (2310 3210);
PAINT ORANGE (2310 3210);
FORCEPROP 2 LASTPIN (2300 3150) $PN 165
J 0
(2310 3160);
DISPLAY 0.617021 (2310 3160);
PAINT ORANGE (2310 3160);
FORCEPROP 2 LASTPIN (2300 3100) $PN 167
J 0
(2310 3110);
DISPLAY 0.617021 (2310 3110);
PAINT ORANGE (2310 3110);
FORCEPROP 2 LASTPIN (2300 3050) $PN 169
J 0
(2310 3060);
DISPLAY 0.617021 (2310 3060);
PAINT ORANGE (2310 3060);
FORCEPROP 2 LASTPIN (2300 3000) $PN 171
J 0
(2310 3010);
DISPLAY 0.617021 (2310 3010);
PAINT ORANGE (2310 3010);
FORCEPROP 2 LASTPIN (2300 2950) $PN 173
J 0
(2310 2960);
DISPLAY 0.617021 (2310 2960);
PAINT ORANGE (2310 2960);
FORCEPROP 2 LASTPIN (2300 2900) $PN 176
J 0
(2310 2910);
DISPLAY 0.617021 (2310 2910);
PAINT ORANGE (2310 2910);
FORCEPROP 2 LASTPIN (2300 2850) $PN 178
J 0
(2310 2860);
DISPLAY 0.617021 (2310 2860);
PAINT ORANGE (2310 2860);
FORCEPROP 2 LASTPIN (2300 2800) $PN 180
J 0
(2310 2810);
DISPLAY 0.617021 (2310 2810);
PAINT ORANGE (2310 2810);
FORCEPROP 2 LASTPIN (2300 2750) $PN 182
J 0
(2310 2760);
DISPLAY 0.617021 (2310 2760);
PAINT ORANGE (2310 2760);
FORCEPROP 2 LASTPIN (2300 2700) $PN 184
J 0
(2310 2710);
DISPLAY 0.617021 (2310 2710);
PAINT ORANGE (2310 2710);
FORCEPROP 2 LASTPIN (2300 2650) $PN 187
J 0
(2310 2660);
DISPLAY 0.617021 (2310 2660);
PAINT ORANGE (2310 2660);
FORCEPROP 2 LASTPIN (2300 2600) $PN 189
J 0
(2310 2610);
DISPLAY 0.617021 (2310 2610);
PAINT ORANGE (2310 2610);
FORCEPROP 2 LASTPIN (2300 2550) $PN 191
J 0
(2310 2560);
DISPLAY 0.617021 (2310 2560);
PAINT ORANGE (2310 2560);
FORCEPROP 2 LASTPIN (2300 2500) $PN 193
J 0
(2310 2510);
DISPLAY 0.617021 (2310 2510);
PAINT ORANGE (2310 2510);
FORCEPROP 2 LASTPIN (2300 2450) $PN 195
J 0
(2310 2460);
DISPLAY 0.617021 (2310 2460);
PAINT ORANGE (2310 2460);
FORCEPROP 2 LASTPIN (2300 2400) $PN 198
J 0
(2310 2410);
DISPLAY 0.617021 (2310 2410);
PAINT ORANGE (2310 2410);
FORCEPROP 2 LASTPIN (2300 2350) $PN 200
J 0
(2310 2360);
DISPLAY 0.617021 (2310 2360);
PAINT ORANGE (2310 2360);
FORCEPROP 2 LASTPIN (2300 2300) $PN 202
J 0
(2310 2310);
DISPLAY 0.617021 (2310 2310);
PAINT ORANGE (2310 2310);
FORCEPROP 2 LASTPIN (2300 2250) $PN 239
J 0
(2310 2260);
DISPLAY 0.617021 (2310 2260);
PAINT ORANGE (2310 2260);
FORCEPROP 2 LASTPIN (2300 2200) $PN 241
J 0
(2310 2210);
DISPLAY 0.617021 (2310 2210);
PAINT ORANGE (2310 2210);
FORCEPROP 2 LASTPIN (2300 2150) $PN 243
J 0
(2310 2160);
DISPLAY 0.617021 (2310 2160);
PAINT ORANGE (2310 2160);
FORCEPROP 2 LASTPIN (2300 2100) $PN 246
J 0
(2310 2110);
DISPLAY 0.617021 (2310 2110);
PAINT ORANGE (2310 2110);
FORCEPROP 2 LASTPIN (2300 2050) $PN 248
J 0
(2310 2060);
DISPLAY 0.617021 (2310 2060);
PAINT ORANGE (2310 2060);
FORCEPROP 2 LASTPIN (2300 2000) $PN 250
J 0
(2310 2010);
DISPLAY 0.617021 (2310 2010);
PAINT ORANGE (2310 2010);
FORCEPROP 2 LASTPIN (2300 1950) $PN 252
J 0
(2310 1960);
DISPLAY 0.617021 (2310 1960);
PAINT ORANGE (2310 1960);
FORCEPROP 2 LASTPIN (2300 1900) $PN 254
J 0
(2310 1910);
DISPLAY 0.617021 (2310 1910);
PAINT ORANGE (2310 1910);
FORCEPROP 2 LASTPIN (2300 1850) $PN 257
J 0
(2310 1860);
DISPLAY 0.617021 (2310 1860);
PAINT ORANGE (2310 1860);
FORCEPROP 2 LASTPIN (2300 1800) $PN 259
J 0
(2310 1810);
DISPLAY 0.617021 (2310 1810);
PAINT ORANGE (2310 1810);
FORCEPROP 2 LASTPIN (2300 1750) $PN 261
J 0
(2310 1760);
DISPLAY 0.617021 (2310 1760);
PAINT ORANGE (2310 1760);
FORCEPROP 2 LASTPIN (2300 1700) $PN 263
J 0
(2310 1710);
DISPLAY 0.617021 (2310 1710);
PAINT ORANGE (2310 1710);
FORCEPROP 2 LASTPIN (2300 1650) $PN 265
J 0
(2310 1660);
DISPLAY 0.617021 (2310 1660);
PAINT ORANGE (2310 1660);
FORCEPROP 2 LASTPIN (2300 1600) $PN 268
J 0
(2310 1610);
DISPLAY 0.617021 (2310 1610);
PAINT ORANGE (2310 1610);
FORCEPROP 2 LASTPIN (2300 1550) $PN 270
J 0
(2310 1560);
DISPLAY 0.617021 (2310 1560);
PAINT ORANGE (2310 1560);
FORCEPROP 2 LASTPIN (2300 1500) $PN 272
J 0
(2310 1510);
DISPLAY 0.617021 (2310 1510);
PAINT ORANGE (2310 1510);
FORCEPROP 2 LASTPIN (2300 1450) $PN 274
J 0
(2310 1460);
DISPLAY 0.617021 (2310 1460);
PAINT ORANGE (2310 1460);
FORCEPROP 2 LASTPIN (2300 1400) $PN 276
J 0
(2310 1410);
DISPLAY 0.617021 (2310 1410);
PAINT ORANGE (2310 1410);
FORCEPROP 2 LASTPIN (2300 1350) $PN 279
J 0
(2310 1360);
DISPLAY 0.617021 (2310 1360);
PAINT ORANGE (2310 1360);
FORCEPROP 2 LASTPIN (2300 1300) $PN 281
J 0
(2310 1310);
DISPLAY 0.617021 (2310 1310);
PAINT ORANGE (2310 1310);
FORCEPROP 2 LASTPIN (1300 1950) $PN 107
J 2
(1290 1960);
DISPLAY 0.617021 (1290 1960);
PAINT ORANGE (1290 1960);
FORCEPROP 2 LASTPIN (1300 2000) $PN 105
J 2
(1290 2010);
DISPLAY 0.617021 (1290 2010);
PAINT ORANGE (1290 2010);
FORCEPROP 2 LASTPIN (1300 1500) $PN 127
J 2
(1290 1510);
DISPLAY 0.617021 (1290 1510);
PAINT ORANGE (1290 1510);
FORCEPROP 1 LAST PACK_TYPE PIP
J 0
(1350 3850);
PAINT SKYBLUE (1350 3850);
DISPLAY INVISIBLE (1350 3850);
FORCEPROP 2 LAST BOM_COST MEM
J 0
(1800 2400);
PAINT ORANGE (1800 2400);
DISPLAY INVISIBLE (1800 2400);
FORCEPROP 2 LAST CDS_LIB mstr_sconn
J 0
(1800 2400);
PAINT ORANGE (1800 2400);
DISPLAY INVISIBLE (1800 2400);
FORCEPROP 2 LAST SEC_TYPE PIP
J 0
(1350 3850);
DISPLAY 1.021277 (1350 3850);
PAINT ORANGE (1350 3850);
DISPLAY INVISIBLE (1350 3850);
FORCEPROP 2 LAST SEC 3
J 0
(1350 3850);
DISPLAY 0.680851 (1350 3850);
PAINT MONO (1350 3850);
DISPLAY INVISIBLE (1350 3850);
FORCEPROP 2 LAST CDS_LOCATION J1A2
J 0
(1350 3800);
DISPLAY 0.617021 (1350 3800);
PAINT AQUA (1350 3800);
DISPLAY INVISIBLE (1350 3800);
FORCEPROP 1 LAST PATH I43
J 0
(1800 3750);
PAINT GREEN (1800 3750);
DISPLAY INVISIBLE (1800 3750);
FORCEPROP 2 LAST ROOM DDR4_CH_L
J 0
(1800 2400);
PAINT ORANGE (1800 2400);
DISPLAY INVISIBLE (1800 2400);
FORCEADD GND..1
R 2
(1100 1100);
FORCEPROP 3 LASTPIN (1100 1150) SIG_NAME GND\g
J 0
(1110 1160);
DISPLAY 0.659574 (1110 1160);
PAINT MONO (1110 1160);
DISPLAY INVISIBLE (1110 1160);
FORCEPROP 1 LAST VOLTAGE 0
J 0
(1100 1100);
PAINT SKYBLUE (1100 1100);
DISPLAY INVISIBLE (1100 1100);
FORCEPROP 2 LAST BOM_COST MEM
J 0
(1100 1105);
PAINT ORANGE (1100 1105);
DISPLAY INVISIBLE (1100 1105);
FORCEPROP 2 LAST CDS_LIB mstr_symbols
J 0
(1100 1100);
DISPLAY 0.787234 (1100 1100);
PAINT MONO (1100 1100);
DISPLAY INVISIBLE (1100 1100);
FORCEPROP 1 LAST SIZE 1B
J 2
(1025 1050);
DISPLAY 1.170213 (1025 1050);
PAINT GREEN (1025 1050);
DISPLAY INVISIBLE (1025 1050);
FORCEPROP 1 LAST BODY_TYPE PLUMBING
J 2
(1145 1057);
DISPLAY 0.340426 (1145 1057);
PAINT GREEN (1145 1057);
DISPLAY INVISIBLE (1145 1057);
FORCEPROP 1 LAST PATH I44
J 2
(1025 1100);
DISPLAY 0.936170 (1025 1100);
PAINT GREEN (1025 1100);
DISPLAY INVISIBLE (1025 1100);
FORCEPROP 2 LAST ROOM DDR4_CH_D
J 0
(1100 1105);
PAINT ORANGE (1100 1105);
DISPLAY INVISIBLE (1100 1105);
FORCEPROP 1 LAST HDL_POWER GND
J 2
(1100 1250);
DISPLAY 0.553191 (1100 1250);
PAINT GREEN (1100 1250);
DISPLAY INVISIBLE (1100 1250);
FORCEADD OFFPAGE..3
(-1175 4950);
FORCEPROP 2 LAST $XR1 86 
J 0
(-871 4950);
DISPLAY 0.638298 (-871 4950);
PAINT MONO (-871 4950);
FORCEPROP 2 LAST $XR0 61 
J 0
(-961 4950);
DISPLAY 0.638298 (-961 4950);
PAINT MONO (-961 4950);
FORCEPROP 2 LAST CDS_LIB mstr_standard
J 0
(-1175 4950);
DISPLAY 0.787234 (-1175 4950);
PAINT MONO (-1175 4950);
DISPLAY INVISIBLE (-1175 4950);
FORCEPROP 1 LAST OFFPAGE TRUE
J 0
(-850 4825);
DISPLAY 0.936170 (-850 4825);
PAINT GREEN (-850 4825);
DISPLAY INVISIBLE (-850 4825);
FORCEPROP 1 LAST COMMENT_BODY TRUE
J 0
(-1225 4850);
DISPLAY 0.936170 (-1225 4850);
PAINT GREEN (-1225 4850);
DISPLAY INVISIBLE (-1225 4850);
FORCEPROP 2 LAST PATH I45
J 0
(-975 5025);
DISPLAY 0.787234 (-975 5025);
PAINT MONO (-975 5025);
DISPLAY INVISIBLE (-975 5025);
FORCEADD TAP..6
R 2
(-1750 4800);
FORCEPROP 3 LASTPIN (-1800 4800) SIG_NAME M_L_DQ<60>
J 0
(-1790 4810);
DISPLAY 0.659574 (-1790 4810);
PAINT MONO (-1790 4810);
DISPLAY INVISIBLE (-1790 4810);
FORCEPROP 1 LASTPIN (-1800 4800) BN 60
J 2
(-1750 4810);
DISPLAY 0.617021 (-1750 4810);
PAINT PINK (-1750 4810);
FORCEPROP 2 LAST CDS_LIB mstr_standard
J 2
(-1750 4800);
DISPLAY 0.787234 (-1750 4800);
PAINT MONO (-1750 4800);
DISPLAY INVISIBLE (-1750 4800);
FORCEPROP 1 LAST BODY_TYPE PLUMBING
J 2
(-1750 4750);
DISPLAY 1.234043 (-1750 4750);
PAINT GREEN (-1750 4750);
DISPLAY INVISIBLE (-1750 4750);
FORCEPROP 1 LAST HDL_TAP TRUE
J 2
(-2075 4675);
DISPLAY 1.234043 (-2075 4675);
PAINT GREEN (-2075 4675);
DISPLAY INVISIBLE (-2075 4675);
FORCEPROP 1 LAST PATH I46
J 2
(-1750 4800);
DISPLAY 0.936170 (-1750 4800);
PAINT GREEN (-1750 4800);
DISPLAY INVISIBLE (-1750 4800);
FORCEADD TAP..6
R 2
(-1750 4750);
FORCEPROP 3 LASTPIN (-1800 4750) SIG_NAME M_L_DQ<61>
J 0
(-1790 4760);
DISPLAY 0.659574 (-1790 4760);
PAINT MONO (-1790 4760);
DISPLAY INVISIBLE (-1790 4760);
FORCEPROP 1 LASTPIN (-1800 4750) BN 61
J 2
(-1750 4760);
DISPLAY 0.617021 (-1750 4760);
PAINT PINK (-1750 4760);
FORCEPROP 2 LAST CDS_LIB mstr_standard
J 2
(-1750 4750);
DISPLAY 0.787234 (-1750 4750);
PAINT MONO (-1750 4750);
DISPLAY INVISIBLE (-1750 4750);
FORCEPROP 1 LAST BODY_TYPE PLUMBING
J 2
(-1750 4700);
DISPLAY 1.234043 (-1750 4700);
PAINT GREEN (-1750 4700);
DISPLAY INVISIBLE (-1750 4700);
FORCEPROP 1 LAST HDL_TAP TRUE
J 2
(-2075 4625);
DISPLAY 1.234043 (-2075 4625);
PAINT GREEN (-2075 4625);
DISPLAY INVISIBLE (-2075 4625);
FORCEPROP 1 LAST PATH I47
J 2
(-1750 4750);
DISPLAY 0.936170 (-1750 4750);
PAINT GREEN (-1750 4750);
DISPLAY INVISIBLE (-1750 4750);
FORCEADD TAP..6
R 2
(-1750 4850);
FORCEPROP 3 LASTPIN (-1800 4850) SIG_NAME M_L_DQ<63>
J 0
(-1790 4860);
DISPLAY 0.659574 (-1790 4860);
PAINT MONO (-1790 4860);
DISPLAY INVISIBLE (-1790 4860);
FORCEPROP 1 LASTPIN (-1800 4850) BN 63
J 2
(-1750 4860);
DISPLAY 0.617021 (-1750 4860);
PAINT PINK (-1750 4860);
FORCEPROP 2 LAST CDS_LIB mstr_standard
J 2
(-1750 4850);
DISPLAY 0.787234 (-1750 4850);
PAINT MONO (-1750 4850);
DISPLAY INVISIBLE (-1750 4850);
FORCEPROP 1 LAST BODY_TYPE PLUMBING
J 2
(-1750 4800);
DISPLAY 1.234043 (-1750 4800);
PAINT GREEN (-1750 4800);
DISPLAY INVISIBLE (-1750 4800);
FORCEPROP 1 LAST HDL_TAP TRUE
J 2
(-2075 4725);
DISPLAY 1.234043 (-2075 4725);
PAINT GREEN (-2075 4725);
DISPLAY INVISIBLE (-2075 4725);
FORCEPROP 1 LAST PATH I48
J 2
(-1750 4850);
DISPLAY 0.936170 (-1750 4850);
PAINT GREEN (-1750 4850);
DISPLAY INVISIBLE (-1750 4850);
FORCEADD TAP..6
R 2
(-1750 4900);
FORCEPROP 3 LASTPIN (-1800 4900) SIG_NAME M_L_DQ<62>
J 0
(-1790 4910);
DISPLAY 0.659574 (-1790 4910);
PAINT MONO (-1790 4910);
DISPLAY INVISIBLE (-1790 4910);
FORCEPROP 1 LASTPIN (-1800 4900) BN 62
J 2
(-1750 4910);
DISPLAY 0.617021 (-1750 4910);
PAINT PINK (-1750 4910);
FORCEPROP 2 LAST CDS_LIB mstr_standard
J 2
(-1750 4900);
DISPLAY 0.787234 (-1750 4900);
PAINT MONO (-1750 4900);
DISPLAY INVISIBLE (-1750 4900);
FORCEPROP 1 LAST BODY_TYPE PLUMBING
J 2
(-1750 4850);
DISPLAY 1.234043 (-1750 4850);
PAINT GREEN (-1750 4850);
DISPLAY INVISIBLE (-1750 4850);
FORCEPROP 1 LAST HDL_TAP TRUE
J 2
(-2075 4775);
DISPLAY 1.234043 (-2075 4775);
PAINT GREEN (-2075 4775);
DISPLAY INVISIBLE (-2075 4775);
FORCEPROP 1 LAST PATH I49
J 2
(-1750 4900);
DISPLAY 0.936170 (-1750 4900);
PAINT GREEN (-1750 4900);
DISPLAY INVISIBLE (-1750 4900);
FORCEADD TAP..6
R 2
(900 5000);
FORCEPROP 3 LASTPIN (850 5000) SIG_NAME M_L_DQS_DN<16>
J 0
(860 5010);
DISPLAY 0.659574 (860 5010);
PAINT MONO (860 5010);
DISPLAY INVISIBLE (860 5010);
FORCEPROP 1 LASTPIN (850 5000) BN 16
J 2
(900 5010);
DISPLAY 0.617021 (900 5010);
PAINT PINK (900 5010);
FORCEPROP 2 LAST CDS_LIB mstr_standard
J 0
(900 5000);
DISPLAY 0.787234 (900 5000);
PAINT MONO (900 5000);
DISPLAY INVISIBLE (900 5000);
FORCEPROP 1 LAST BODY_TYPE PLUMBING
J 2
(900 4950);
DISPLAY 1.234043 (900 4950);
PAINT GREEN (900 4950);
DISPLAY INVISIBLE (900 4950);
FORCEPROP 1 LAST HDL_TAP TRUE
J 2
(575 4875);
DISPLAY 1.234043 (575 4875);
PAINT GREEN (575 4875);
DISPLAY INVISIBLE (575 4875);
FORCEPROP 1 LAST PATH I5
J 2
(900 5000);
DISPLAY 0.936170 (900 5000);
PAINT GREEN (900 5000);
DISPLAY INVISIBLE (900 5000);
FORCEADD TAP..6
R 2
(-1750 4500);
FORCEPROP 3 LASTPIN (-1800 4500) SIG_NAME M_L_DQ<54>
J 0
(-1790 4510);
DISPLAY 0.659574 (-1790 4510);
PAINT MONO (-1790 4510);
DISPLAY INVISIBLE (-1790 4510);
FORCEPROP 1 LASTPIN (-1800 4500) BN 54
J 2
(-1750 4510);
DISPLAY 0.617021 (-1750 4510);
PAINT PINK (-1750 4510);
FORCEPROP 2 LAST CDS_LIB mstr_standard
J 2
(-1750 4500);
DISPLAY 0.787234 (-1750 4500);
PAINT MONO (-1750 4500);
DISPLAY INVISIBLE (-1750 4500);
FORCEPROP 1 LAST BODY_TYPE PLUMBING
J 2
(-1750 4450);
DISPLAY 1.234043 (-1750 4450);
PAINT GREEN (-1750 4450);
DISPLAY INVISIBLE (-1750 4450);
FORCEPROP 1 LAST HDL_TAP TRUE
J 2
(-2075 4375);
DISPLAY 1.234043 (-2075 4375);
PAINT GREEN (-2075 4375);
DISPLAY INVISIBLE (-2075 4375);
FORCEPROP 1 LAST PATH I50
J 2
(-1750 4500);
DISPLAY 0.936170 (-1750 4500);
PAINT GREEN (-1750 4500);
DISPLAY INVISIBLE (-1750 4500);
FORCEADD TAP..6
R 2
(-1750 4550);
FORCEPROP 3 LASTPIN (-1800 4550) SIG_NAME M_L_DQ<57>
J 0
(-1790 4560);
DISPLAY 0.659574 (-1790 4560);
PAINT MONO (-1790 4560);
DISPLAY INVISIBLE (-1790 4560);
FORCEPROP 1 LASTPIN (-1800 4550) BN 57
J 2
(-1750 4560);
DISPLAY 0.617021 (-1750 4560);
PAINT PINK (-1750 4560);
FORCEPROP 2 LAST CDS_LIB mstr_standard
J 2
(-1750 4550);
DISPLAY 0.787234 (-1750 4550);
PAINT MONO (-1750 4550);
DISPLAY INVISIBLE (-1750 4550);
FORCEPROP 1 LAST BODY_TYPE PLUMBING
J 2
(-1750 4500);
DISPLAY 1.234043 (-1750 4500);
PAINT GREEN (-1750 4500);
DISPLAY INVISIBLE (-1750 4500);
FORCEPROP 1 LAST HDL_TAP TRUE
J 2
(-2075 4425);
DISPLAY 1.234043 (-2075 4425);
PAINT GREEN (-2075 4425);
DISPLAY INVISIBLE (-2075 4425);
FORCEPROP 1 LAST PATH I51
J 2
(-1750 4550);
DISPLAY 0.936170 (-1750 4550);
PAINT GREEN (-1750 4550);
DISPLAY INVISIBLE (-1750 4550);
FORCEADD TAP..6
R 2
(-1750 4650);
FORCEPROP 3 LASTPIN (-1800 4650) SIG_NAME M_L_DQ<59>
J 0
(-1790 4660);
DISPLAY 0.659574 (-1790 4660);
PAINT MONO (-1790 4660);
DISPLAY INVISIBLE (-1790 4660);
FORCEPROP 1 LASTPIN (-1800 4650) BN 59
J 2
(-1750 4660);
DISPLAY 0.617021 (-1750 4660);
PAINT PINK (-1750 4660);
FORCEPROP 2 LAST CDS_LIB mstr_standard
J 2
(-1750 4650);
DISPLAY 0.787234 (-1750 4650);
PAINT MONO (-1750 4650);
DISPLAY INVISIBLE (-1750 4650);
FORCEPROP 1 LAST BODY_TYPE PLUMBING
J 2
(-1750 4600);
DISPLAY 1.234043 (-1750 4600);
PAINT GREEN (-1750 4600);
DISPLAY INVISIBLE (-1750 4600);
FORCEPROP 1 LAST HDL_TAP TRUE
J 2
(-2075 4525);
DISPLAY 1.234043 (-2075 4525);
PAINT GREEN (-2075 4525);
DISPLAY INVISIBLE (-2075 4525);
FORCEPROP 1 LAST PATH I52
J 2
(-1750 4650);
DISPLAY 0.936170 (-1750 4650);
PAINT GREEN (-1750 4650);
DISPLAY INVISIBLE (-1750 4650);
FORCEADD TAP..6
R 2
(-1750 4600);
FORCEPROP 3 LASTPIN (-1800 4600) SIG_NAME M_L_DQ<56>
J 0
(-1790 4610);
DISPLAY 0.659574 (-1790 4610);
PAINT MONO (-1790 4610);
DISPLAY INVISIBLE (-1790 4610);
FORCEPROP 1 LASTPIN (-1800 4600) BN 56
J 2
(-1750 4610);
DISPLAY 0.617021 (-1750 4610);
PAINT PINK (-1750 4610);
FORCEPROP 2 LAST CDS_LIB mstr_standard
J 2
(-1750 4600);
DISPLAY 0.787234 (-1750 4600);
PAINT MONO (-1750 4600);
DISPLAY INVISIBLE (-1750 4600);
FORCEPROP 1 LAST BODY_TYPE PLUMBING
J 2
(-1750 4550);
DISPLAY 1.234043 (-1750 4550);
PAINT GREEN (-1750 4550);
DISPLAY INVISIBLE (-1750 4550);
FORCEPROP 1 LAST HDL_TAP TRUE
J 2
(-2075 4475);
DISPLAY 1.234043 (-2075 4475);
PAINT GREEN (-2075 4475);
DISPLAY INVISIBLE (-2075 4475);
FORCEPROP 1 LAST PATH I53
J 2
(-1750 4600);
DISPLAY 0.936170 (-1750 4600);
PAINT GREEN (-1750 4600);
DISPLAY INVISIBLE (-1750 4600);
FORCEADD TAP..6
R 2
(-1750 4700);
FORCEPROP 3 LASTPIN (-1800 4700) SIG_NAME M_L_DQ<58>
J 0
(-1790 4710);
DISPLAY 0.659574 (-1790 4710);
PAINT MONO (-1790 4710);
DISPLAY INVISIBLE (-1790 4710);
FORCEPROP 1 LASTPIN (-1800 4700) BN 58
J 2
(-1750 4710);
DISPLAY 0.617021 (-1750 4710);
PAINT PINK (-1750 4710);
FORCEPROP 2 LAST CDS_LIB mstr_standard
J 2
(-1750 4700);
DISPLAY 0.787234 (-1750 4700);
PAINT MONO (-1750 4700);
DISPLAY INVISIBLE (-1750 4700);
FORCEPROP 1 LAST BODY_TYPE PLUMBING
J 2
(-1750 4650);
DISPLAY 1.234043 (-1750 4650);
PAINT GREEN (-1750 4650);
DISPLAY INVISIBLE (-1750 4650);
FORCEPROP 1 LAST HDL_TAP TRUE
J 2
(-2075 4575);
DISPLAY 1.234043 (-2075 4575);
PAINT GREEN (-2075 4575);
DISPLAY INVISIBLE (-2075 4575);
FORCEPROP 1 LAST PATH I54
J 2
(-1750 4700);
DISPLAY 0.936170 (-1750 4700);
PAINT GREEN (-1750 4700);
DISPLAY INVISIBLE (-1750 4700);
FORCEADD TAP..6
R 2
(-1750 4250);
FORCEPROP 3 LASTPIN (-1800 4250) SIG_NAME M_L_DQ<51>
J 0
(-1790 4260);
DISPLAY 0.659574 (-1790 4260);
PAINT MONO (-1790 4260);
DISPLAY INVISIBLE (-1790 4260);
FORCEPROP 1 LASTPIN (-1800 4250) BN 51
J 2
(-1750 4260);
DISPLAY 0.617021 (-1750 4260);
PAINT PINK (-1750 4260);
FORCEPROP 2 LAST CDS_LIB mstr_standard
J 2
(-1750 4250);
DISPLAY 0.787234 (-1750 4250);
PAINT MONO (-1750 4250);
DISPLAY INVISIBLE (-1750 4250);
FORCEPROP 1 LAST BODY_TYPE PLUMBING
J 2
(-1750 4200);
DISPLAY 1.234043 (-1750 4200);
PAINT GREEN (-1750 4200);
DISPLAY INVISIBLE (-1750 4200);
FORCEPROP 1 LAST HDL_TAP TRUE
J 2
(-2075 4125);
DISPLAY 1.234043 (-2075 4125);
PAINT GREEN (-2075 4125);
DISPLAY INVISIBLE (-2075 4125);
FORCEPROP 1 LAST PATH I55
J 2
(-1750 4250);
DISPLAY 0.936170 (-1750 4250);
PAINT GREEN (-1750 4250);
DISPLAY INVISIBLE (-1750 4250);
FORCEADD TAP..6
R 2
(-1750 4300);
FORCEPROP 3 LASTPIN (-1800 4300) SIG_NAME M_L_DQ<50>
J 0
(-1790 4310);
DISPLAY 0.659574 (-1790 4310);
PAINT MONO (-1790 4310);
DISPLAY INVISIBLE (-1790 4310);
FORCEPROP 1 LASTPIN (-1800 4300) BN 50
J 2
(-1750 4310);
DISPLAY 0.617021 (-1750 4310);
PAINT PINK (-1750 4310);
FORCEPROP 2 LAST CDS_LIB mstr_standard
J 2
(-1750 4300);
DISPLAY 0.787234 (-1750 4300);
PAINT MONO (-1750 4300);
DISPLAY INVISIBLE (-1750 4300);
FORCEPROP 1 LAST BODY_TYPE PLUMBING
J 2
(-1750 4250);
DISPLAY 1.234043 (-1750 4250);
PAINT GREEN (-1750 4250);
DISPLAY INVISIBLE (-1750 4250);
FORCEPROP 1 LAST HDL_TAP TRUE
J 2
(-2075 4175);
DISPLAY 1.234043 (-2075 4175);
PAINT GREEN (-2075 4175);
DISPLAY INVISIBLE (-2075 4175);
FORCEPROP 1 LAST PATH I56
J 2
(-1750 4300);
DISPLAY 0.936170 (-1750 4300);
PAINT GREEN (-1750 4300);
DISPLAY INVISIBLE (-1750 4300);
FORCEADD TAP..6
R 2
(-1750 4350);
FORCEPROP 3 LASTPIN (-1800 4350) SIG_NAME M_L_DQ<53>
J 0
(-1790 4360);
DISPLAY 0.659574 (-1790 4360);
PAINT MONO (-1790 4360);
DISPLAY INVISIBLE (-1790 4360);
FORCEPROP 1 LASTPIN (-1800 4350) BN 53
J 2
(-1750 4360);
DISPLAY 0.617021 (-1750 4360);
PAINT PINK (-1750 4360);
FORCEPROP 2 LAST CDS_LIB mstr_standard
J 2
(-1750 4350);
DISPLAY 0.787234 (-1750 4350);
PAINT MONO (-1750 4350);
DISPLAY INVISIBLE (-1750 4350);
FORCEPROP 1 LAST BODY_TYPE PLUMBING
J 2
(-1750 4300);
DISPLAY 1.234043 (-1750 4300);
PAINT GREEN (-1750 4300);
DISPLAY INVISIBLE (-1750 4300);
FORCEPROP 1 LAST HDL_TAP TRUE
J 2
(-2075 4225);
DISPLAY 1.234043 (-2075 4225);
PAINT GREEN (-2075 4225);
DISPLAY INVISIBLE (-2075 4225);
FORCEPROP 1 LAST PATH I57
J 2
(-1750 4350);
DISPLAY 0.936170 (-1750 4350);
PAINT GREEN (-1750 4350);
DISPLAY INVISIBLE (-1750 4350);
FORCEADD TAP..6
R 2
(-1750 4450);
FORCEPROP 3 LASTPIN (-1800 4450) SIG_NAME M_L_DQ<55>
J 0
(-1790 4460);
DISPLAY 0.659574 (-1790 4460);
PAINT MONO (-1790 4460);
DISPLAY INVISIBLE (-1790 4460);
FORCEPROP 1 LASTPIN (-1800 4450) BN 55
J 2
(-1750 4460);
DISPLAY 0.617021 (-1750 4460);
PAINT PINK (-1750 4460);
FORCEPROP 2 LAST CDS_LIB mstr_standard
J 2
(-1750 4450);
DISPLAY 0.787234 (-1750 4450);
PAINT MONO (-1750 4450);
DISPLAY INVISIBLE (-1750 4450);
FORCEPROP 1 LAST BODY_TYPE PLUMBING
J 2
(-1750 4400);
DISPLAY 1.234043 (-1750 4400);
PAINT GREEN (-1750 4400);
DISPLAY INVISIBLE (-1750 4400);
FORCEPROP 1 LAST HDL_TAP TRUE
J 2
(-2075 4325);
DISPLAY 1.234043 (-2075 4325);
PAINT GREEN (-2075 4325);
DISPLAY INVISIBLE (-2075 4325);
FORCEPROP 1 LAST PATH I58
J 2
(-1750 4450);
DISPLAY 0.936170 (-1750 4450);
PAINT GREEN (-1750 4450);
DISPLAY INVISIBLE (-1750 4450);
FORCEADD TAP..6
R 2
(-1750 4400);
FORCEPROP 3 LASTPIN (-1800 4400) SIG_NAME M_L_DQ<52>
J 0
(-1790 4410);
DISPLAY 0.659574 (-1790 4410);
PAINT MONO (-1790 4410);
DISPLAY INVISIBLE (-1790 4410);
FORCEPROP 1 LASTPIN (-1800 4400) BN 52
J 2
(-1750 4410);
DISPLAY 0.617021 (-1750 4410);
PAINT PINK (-1750 4410);
FORCEPROP 2 LAST CDS_LIB mstr_standard
J 2
(-1750 4400);
DISPLAY 0.787234 (-1750 4400);
PAINT MONO (-1750 4400);
DISPLAY INVISIBLE (-1750 4400);
FORCEPROP 1 LAST BODY_TYPE PLUMBING
J 2
(-1750 4350);
DISPLAY 1.234043 (-1750 4350);
PAINT GREEN (-1750 4350);
DISPLAY INVISIBLE (-1750 4350);
FORCEPROP 1 LAST HDL_TAP TRUE
J 2
(-2075 4275);
DISPLAY 1.234043 (-2075 4275);
PAINT GREEN (-2075 4275);
DISPLAY INVISIBLE (-2075 4275);
FORCEPROP 1 LAST PATH I59
J 2
(-1750 4400);
DISPLAY 0.936170 (-1750 4400);
PAINT GREEN (-1750 4400);
DISPLAY INVISIBLE (-1750 4400);
FORCEADD TAP..6
R 2
(900 4900);
FORCEPROP 3 LASTPIN (850 4900) SIG_NAME M_L_DQS_DN<15>
J 0
(860 4910);
DISPLAY 0.659574 (860 4910);
PAINT MONO (860 4910);
DISPLAY INVISIBLE (860 4910);
FORCEPROP 1 LASTPIN (850 4900) BN 15
J 2
(900 4910);
DISPLAY 0.617021 (900 4910);
PAINT PINK (900 4910);
FORCEPROP 2 LAST CDS_LIB mstr_standard
J 0
(900 4900);
DISPLAY 0.787234 (900 4900);
PAINT MONO (900 4900);
DISPLAY INVISIBLE (900 4900);
FORCEPROP 1 LAST BODY_TYPE PLUMBING
J 2
(900 4850);
DISPLAY 1.234043 (900 4850);
PAINT GREEN (900 4850);
DISPLAY INVISIBLE (900 4850);
FORCEPROP 1 LAST HDL_TAP TRUE
J 2
(575 4775);
DISPLAY 1.234043 (575 4775);
PAINT GREEN (575 4775);
DISPLAY INVISIBLE (575 4775);
FORCEPROP 1 LAST PATH I6
J 2
(900 4900);
DISPLAY 0.936170 (900 4900);
PAINT GREEN (900 4900);
DISPLAY INVISIBLE (900 4900);
FORCEADD TAP..6
R 2
(-1750 3950);
FORCEPROP 3 LASTPIN (-1800 3950) SIG_NAME M_L_DQ<45>
J 0
(-1790 3960);
DISPLAY 0.659574 (-1790 3960);
PAINT MONO (-1790 3960);
DISPLAY INVISIBLE (-1790 3960);
FORCEPROP 1 LASTPIN (-1800 3950) BN 45
J 2
(-1750 3960);
DISPLAY 0.617021 (-1750 3960);
PAINT PINK (-1750 3960);
FORCEPROP 2 LAST CDS_LIB mstr_standard
J 2
(-1750 3950);
DISPLAY 0.787234 (-1750 3950);
PAINT MONO (-1750 3950);
DISPLAY INVISIBLE (-1750 3950);
FORCEPROP 1 LAST BODY_TYPE PLUMBING
J 2
(-1750 3900);
DISPLAY 1.234043 (-1750 3900);
PAINT GREEN (-1750 3900);
DISPLAY INVISIBLE (-1750 3900);
FORCEPROP 1 LAST HDL_TAP TRUE
J 2
(-2075 3825);
DISPLAY 1.234043 (-2075 3825);
PAINT GREEN (-2075 3825);
DISPLAY INVISIBLE (-2075 3825);
FORCEPROP 1 LAST PATH I60
J 2
(-1750 3950);
DISPLAY 0.936170 (-1750 3950);
PAINT GREEN (-1750 3950);
DISPLAY INVISIBLE (-1750 3950);
FORCEADD TAP..6
R 2
(-1750 4000);
FORCEPROP 3 LASTPIN (-1800 4000) SIG_NAME M_L_DQ<44>
J 0
(-1790 4010);
DISPLAY 0.659574 (-1790 4010);
PAINT MONO (-1790 4010);
DISPLAY INVISIBLE (-1790 4010);
FORCEPROP 1 LASTPIN (-1800 4000) BN 44
J 2
(-1750 4010);
DISPLAY 0.617021 (-1750 4010);
PAINT PINK (-1750 4010);
FORCEPROP 2 LAST CDS_LIB mstr_standard
J 2
(-1750 4000);
DISPLAY 0.787234 (-1750 4000);
PAINT MONO (-1750 4000);
DISPLAY INVISIBLE (-1750 4000);
FORCEPROP 1 LAST BODY_TYPE PLUMBING
J 2
(-1750 3950);
DISPLAY 1.234043 (-1750 3950);
PAINT GREEN (-1750 3950);
DISPLAY INVISIBLE (-1750 3950);
FORCEPROP 1 LAST HDL_TAP TRUE
J 2
(-2075 3875);
DISPLAY 1.234043 (-2075 3875);
PAINT GREEN (-2075 3875);
DISPLAY INVISIBLE (-2075 3875);
FORCEPROP 1 LAST PATH I61
J 2
(-1750 4000);
DISPLAY 0.936170 (-1750 4000);
PAINT GREEN (-1750 4000);
DISPLAY INVISIBLE (-1750 4000);
FORCEADD TAP..6
R 2
(-1750 4050);
FORCEPROP 3 LASTPIN (-1800 4050) SIG_NAME M_L_DQ<47>
J 0
(-1790 4060);
DISPLAY 0.659574 (-1790 4060);
PAINT MONO (-1790 4060);
DISPLAY INVISIBLE (-1790 4060);
FORCEPROP 1 LASTPIN (-1800 4050) BN 47
J 2
(-1750 4060);
DISPLAY 0.617021 (-1750 4060);
PAINT PINK (-1750 4060);
FORCEPROP 2 LAST CDS_LIB mstr_standard
J 2
(-1750 4050);
DISPLAY 0.787234 (-1750 4050);
PAINT MONO (-1750 4050);
DISPLAY INVISIBLE (-1750 4050);
FORCEPROP 1 LAST BODY_TYPE PLUMBING
J 2
(-1750 4000);
DISPLAY 1.234043 (-1750 4000);
PAINT GREEN (-1750 4000);
DISPLAY INVISIBLE (-1750 4000);
FORCEPROP 1 LAST HDL_TAP TRUE
J 2
(-2075 3925);
DISPLAY 1.234043 (-2075 3925);
PAINT GREEN (-2075 3925);
DISPLAY INVISIBLE (-2075 3925);
FORCEPROP 1 LAST PATH I62
J 2
(-1750 4050);
DISPLAY 0.936170 (-1750 4050);
PAINT GREEN (-1750 4050);
DISPLAY INVISIBLE (-1750 4050);
FORCEADD TAP..6
R 2
(-1750 4150);
FORCEPROP 3 LASTPIN (-1800 4150) SIG_NAME M_L_DQ<49>
J 0
(-1790 4160);
DISPLAY 0.659574 (-1790 4160);
PAINT MONO (-1790 4160);
DISPLAY INVISIBLE (-1790 4160);
FORCEPROP 1 LASTPIN (-1800 4150) BN 49
J 2
(-1750 4160);
DISPLAY 0.617021 (-1750 4160);
PAINT PINK (-1750 4160);
FORCEPROP 2 LAST CDS_LIB mstr_standard
J 2
(-1750 4150);
DISPLAY 0.787234 (-1750 4150);
PAINT MONO (-1750 4150);
DISPLAY INVISIBLE (-1750 4150);
FORCEPROP 1 LAST BODY_TYPE PLUMBING
J 2
(-1750 4100);
DISPLAY 1.234043 (-1750 4100);
PAINT GREEN (-1750 4100);
DISPLAY INVISIBLE (-1750 4100);
FORCEPROP 1 LAST HDL_TAP TRUE
J 2
(-2075 4025);
DISPLAY 1.234043 (-2075 4025);
PAINT GREEN (-2075 4025);
DISPLAY INVISIBLE (-2075 4025);
FORCEPROP 1 LAST PATH I63
J 2
(-1750 4150);
DISPLAY 0.936170 (-1750 4150);
PAINT GREEN (-1750 4150);
DISPLAY INVISIBLE (-1750 4150);
FORCEADD TAP..6
R 2
(-1750 4100);
FORCEPROP 3 LASTPIN (-1800 4100) SIG_NAME M_L_DQ<46>
J 0
(-1790 4110);
DISPLAY 0.659574 (-1790 4110);
PAINT MONO (-1790 4110);
DISPLAY INVISIBLE (-1790 4110);
FORCEPROP 1 LASTPIN (-1800 4100) BN 46
J 2
(-1750 4110);
DISPLAY 0.617021 (-1750 4110);
PAINT PINK (-1750 4110);
FORCEPROP 2 LAST CDS_LIB mstr_standard
J 2
(-1750 4100);
DISPLAY 0.787234 (-1750 4100);
PAINT MONO (-1750 4100);
DISPLAY INVISIBLE (-1750 4100);
FORCEPROP 1 LAST BODY_TYPE PLUMBING
J 2
(-1750 4050);
DISPLAY 1.234043 (-1750 4050);
PAINT GREEN (-1750 4050);
DISPLAY INVISIBLE (-1750 4050);
FORCEPROP 1 LAST HDL_TAP TRUE
J 2
(-2075 3975);
DISPLAY 1.234043 (-2075 3975);
PAINT GREEN (-2075 3975);
DISPLAY INVISIBLE (-2075 3975);
FORCEPROP 1 LAST PATH I64
J 2
(-1750 4100);
DISPLAY 0.936170 (-1750 4100);
PAINT GREEN (-1750 4100);
DISPLAY INVISIBLE (-1750 4100);
FORCEADD TAP..6
R 2
(-1750 4200);
FORCEPROP 3 LASTPIN (-1800 4200) SIG_NAME M_L_DQ<48>
J 0
(-1790 4210);
DISPLAY 0.659574 (-1790 4210);
PAINT MONO (-1790 4210);
DISPLAY INVISIBLE (-1790 4210);
FORCEPROP 1 LASTPIN (-1800 4200) BN 48
J 2
(-1750 4210);
DISPLAY 0.617021 (-1750 4210);
PAINT PINK (-1750 4210);
FORCEPROP 2 LAST CDS_LIB mstr_standard
J 2
(-1750 4200);
DISPLAY 0.787234 (-1750 4200);
PAINT MONO (-1750 4200);
DISPLAY INVISIBLE (-1750 4200);
FORCEPROP 1 LAST BODY_TYPE PLUMBING
J 2
(-1750 4150);
DISPLAY 1.234043 (-1750 4150);
PAINT GREEN (-1750 4150);
DISPLAY INVISIBLE (-1750 4150);
FORCEPROP 1 LAST HDL_TAP TRUE
J 2
(-2075 4075);
DISPLAY 1.234043 (-2075 4075);
PAINT GREEN (-2075 4075);
DISPLAY INVISIBLE (-2075 4075);
FORCEPROP 1 LAST PATH I65
J 2
(-1750 4200);
DISPLAY 0.936170 (-1750 4200);
PAINT GREEN (-1750 4200);
DISPLAY INVISIBLE (-1750 4200);
FORCEADD SCONN288_H44441004..2
(0 4300);
FORCEPROP 1 LAST LOCATION J1A2
J 0
(-400 5400);
DISPLAY 0.617021 (-400 5400);
PAINT AQUA (-400 5400);
FORCEPROP 1 LAST PART_NUMBER H44441-004
J 0
(-400 3200);
DISPLAY 0.617021 (-400 3200);
PAINT BLUE (-400 3200);
FORCEPROP 1 LAST MATERIAL SCONN
J 0
(-400 5350);
DISPLAY 0.617021 (-400 5350);
PAINT SKYBLUE (-400 5350);
FORCEPROP 2 LASTPIN (450 5150) $PN 51
J 0
(460 5160);
DISPLAY 0.617021 (460 5160);
PAINT ORANGE (460 5160);
FORCEPROP 2 LASTPIN (450 5100) $PN 52
J 0
(460 5110);
DISPLAY 0.617021 (460 5110);
PAINT ORANGE (460 5110);
FORCEPROP 2 LASTPIN (450 5050) $PN 132
J 0
(460 5060);
DISPLAY 0.617021 (460 5060);
PAINT ORANGE (460 5060);
FORCEPROP 2 LASTPIN (450 5000) $PN 133
J 0
(460 5010);
DISPLAY 0.617021 (460 5010);
PAINT ORANGE (460 5010);
FORCEPROP 2 LASTPIN (450 4950) $PN 121
J 0
(460 4960);
DISPLAY 0.617021 (460 4960);
PAINT ORANGE (460 4960);
FORCEPROP 2 LASTPIN (450 4900) $PN 122
J 0
(460 4910);
DISPLAY 0.617021 (460 4910);
PAINT ORANGE (460 4910);
FORCEPROP 2 LASTPIN (450 4850) $PN 110
J 0
(460 4860);
DISPLAY 0.617021 (460 4860);
PAINT ORANGE (460 4860);
FORCEPROP 2 LASTPIN (450 4800) $PN 111
J 0
(460 4810);
DISPLAY 0.617021 (460 4810);
PAINT ORANGE (460 4810);
FORCEPROP 2 LASTPIN (450 4750) $PN 99
J 0
(460 4760);
DISPLAY 0.617021 (460 4760);
PAINT ORANGE (460 4760);
FORCEPROP 2 LASTPIN (450 4700) $PN 100
J 0
(460 4710);
DISPLAY 0.617021 (460 4710);
PAINT ORANGE (460 4710);
FORCEPROP 2 LASTPIN (450 4650) $PN 40
J 0
(460 4660);
DISPLAY 0.617021 (460 4660);
PAINT ORANGE (460 4660);
FORCEPROP 2 LASTPIN (450 4600) $PN 41
J 0
(460 4610);
DISPLAY 0.617021 (460 4610);
PAINT ORANGE (460 4610);
FORCEPROP 2 LASTPIN (450 4550) $PN 29
J 0
(460 4560);
DISPLAY 0.617021 (460 4560);
PAINT ORANGE (460 4560);
FORCEPROP 2 LASTPIN (450 4500) $PN 30
J 0
(460 4510);
DISPLAY 0.617021 (460 4510);
PAINT ORANGE (460 4510);
FORCEPROP 2 LASTPIN (450 4450) $PN 18
J 0
(460 4460);
DISPLAY 0.617021 (460 4460);
PAINT ORANGE (460 4460);
FORCEPROP 2 LASTPIN (450 4400) $PN 19
J 0
(460 4410);
DISPLAY 0.617021 (460 4410);
PAINT ORANGE (460 4410);
FORCEPROP 2 LASTPIN (450 4350) $PN 7
J 0
(460 4360);
DISPLAY 0.617021 (460 4360);
PAINT ORANGE (460 4360);
FORCEPROP 2 LASTPIN (450 4300) $PN 8
J 0
(460 4310);
DISPLAY 0.617021 (460 4310);
PAINT ORANGE (460 4310);
FORCEPROP 2 LASTPIN (450 4250) $PN 197
J 0
(460 4260);
DISPLAY 0.617021 (460 4260);
PAINT ORANGE (460 4260);
FORCEPROP 2 LASTPIN (450 4200) $PN 196
J 0
(460 4210);
DISPLAY 0.617021 (460 4210);
PAINT ORANGE (460 4210);
FORCEPROP 2 LASTPIN (450 4150) $PN 278
J 0
(460 4160);
DISPLAY 0.617021 (460 4160);
PAINT ORANGE (460 4160);
FORCEPROP 2 LASTPIN (450 4100) $PN 277
J 0
(460 4110);
DISPLAY 0.617021 (460 4110);
PAINT ORANGE (460 4110);
FORCEPROP 2 LASTPIN (450 4050) $PN 267
J 0
(460 4060);
DISPLAY 0.617021 (460 4060);
PAINT ORANGE (460 4060);
FORCEPROP 2 LASTPIN (450 4000) $PN 266
J 0
(460 4010);
DISPLAY 0.617021 (460 4010);
PAINT ORANGE (460 4010);
FORCEPROP 2 LASTPIN (450 3900) $PN 255
J 0
(460 3910);
DISPLAY 0.617021 (460 3910);
PAINT ORANGE (460 3910);
FORCEPROP 2 LASTPIN (450 3850) $PN 245
J 0
(460 3860);
DISPLAY 0.617021 (460 3860);
PAINT ORANGE (460 3860);
FORCEPROP 2 LASTPIN (450 3800) $PN 244
J 0
(460 3810);
DISPLAY 0.617021 (460 3810);
PAINT ORANGE (460 3810);
FORCEPROP 2 LASTPIN (450 3750) $PN 186
J 0
(460 3760);
DISPLAY 0.617021 (460 3760);
PAINT ORANGE (460 3760);
FORCEPROP 2 LASTPIN (450 3650) $PN 175
J 0
(460 3660);
DISPLAY 0.617021 (460 3660);
PAINT ORANGE (460 3660);
FORCEPROP 2 LASTPIN (450 3600) $PN 174
J 0
(460 3610);
DISPLAY 0.617021 (460 3610);
PAINT ORANGE (460 3610);
FORCEPROP 2 LASTPIN (450 3550) $PN 164
J 0
(460 3560);
DISPLAY 0.617021 (460 3560);
PAINT ORANGE (460 3560);
FORCEPROP 2 LASTPIN (450 3500) $PN 163
J 0
(460 3510);
DISPLAY 0.617021 (460 3510);
PAINT ORANGE (460 3510);
FORCEPROP 2 LASTPIN (450 3450) $PN 153
J 0
(460 3460);
DISPLAY 0.617021 (460 3460);
PAINT ORANGE (460 3460);
FORCEPROP 2 LASTPIN (450 3400) $PN 152
J 0
(460 3410);
DISPLAY 0.617021 (460 3410);
PAINT ORANGE (460 3410);
FORCEPROP 2 LASTPIN (450 3700) $PN 185
J 0
(460 3710);
DISPLAY 0.617021 (460 3710);
PAINT ORANGE (460 3710);
FORCEPROP 2 LASTPIN (450 3950) $PN 256
J 0
(460 3960);
DISPLAY 0.617021 (460 3960);
PAINT ORANGE (460 3960);
FORCEPROP 1 LAST PACK_TYPE PIP
J 0
(-400 5450);
PAINT SKYBLUE (-400 5450);
DISPLAY INVISIBLE (-400 5450);
FORCEPROP 2 LAST BOM_COST MEM
J 0
(0 4300);
PAINT ORANGE (0 4300);
DISPLAY INVISIBLE (0 4300);
FORCEPROP 2 LAST CDS_LIB mstr_sconn
J 0
(0 4300);
PAINT ORANGE (0 4300);
DISPLAY INVISIBLE (0 4300);
FORCEPROP 2 LAST SEC_TYPE PIP
J 0
(-400 5450);
DISPLAY 1.021277 (-400 5450);
PAINT ORANGE (-400 5450);
DISPLAY INVISIBLE (-400 5450);
FORCEPROP 2 LAST SEC 2
J 0
(-400 5450);
DISPLAY 0.680851 (-400 5450);
PAINT MONO (-400 5450);
DISPLAY INVISIBLE (-400 5450);
FORCEPROP 2 LAST CDS_LOCATION J1A2
J 0
(-400 5400);
DISPLAY 0.617021 (-400 5400);
PAINT AQUA (-400 5400);
DISPLAY INVISIBLE (-400 5400);
FORCEPROP 1 LAST PATH I66
J 0
(0 5350);
PAINT GREEN (0 5350);
DISPLAY INVISIBLE (0 5350);
FORCEPROP 2 LAST ROOM DDR4_CH_L
J 0
(-400 5500);
PAINT ORANGE (-400 5500);
DISPLAY INVISIBLE (-400 5500);
FORCEADD TAP..6
R 2
(-1750 3800);
FORCEPROP 3 LASTPIN (-1800 3800) SIG_NAME M_L_DQ<40>
J 0
(-1790 3810);
DISPLAY 0.659574 (-1790 3810);
PAINT MONO (-1790 3810);
DISPLAY INVISIBLE (-1790 3810);
FORCEPROP 1 LASTPIN (-1800 3800) BN 40
J 2
(-1750 3810);
DISPLAY 0.617021 (-1750 3810);
PAINT PINK (-1750 3810);
FORCEPROP 2 LAST CDS_LIB mstr_standard
J 2
(-1750 3800);
DISPLAY 0.787234 (-1750 3800);
PAINT MONO (-1750 3800);
DISPLAY INVISIBLE (-1750 3800);
FORCEPROP 1 LAST BODY_TYPE PLUMBING
J 2
(-1750 3750);
DISPLAY 1.234043 (-1750 3750);
PAINT GREEN (-1750 3750);
DISPLAY INVISIBLE (-1750 3750);
FORCEPROP 1 LAST HDL_TAP TRUE
J 2
(-2075 3675);
DISPLAY 1.234043 (-2075 3675);
PAINT GREEN (-2075 3675);
DISPLAY INVISIBLE (-2075 3675);
FORCEPROP 1 LAST PATH I67
J 2
(-1750 3800);
DISPLAY 0.936170 (-1750 3800);
PAINT GREEN (-1750 3800);
DISPLAY INVISIBLE (-1750 3800);
FORCEADD TAP..6
R 2
(-1750 3700);
FORCEPROP 3 LASTPIN (-1800 3700) SIG_NAME M_L_DQ<38>
J 0
(-1790 3710);
DISPLAY 0.659574 (-1790 3710);
PAINT MONO (-1790 3710);
DISPLAY INVISIBLE (-1790 3710);
FORCEPROP 1 LASTPIN (-1800 3700) BN 38
J 2
(-1750 3710);
DISPLAY 0.617021 (-1750 3710);
PAINT PINK (-1750 3710);
FORCEPROP 2 LAST CDS_LIB mstr_standard
J 2
(-1750 3700);
DISPLAY 0.787234 (-1750 3700);
PAINT MONO (-1750 3700);
DISPLAY INVISIBLE (-1750 3700);
FORCEPROP 1 LAST BODY_TYPE PLUMBING
J 2
(-1750 3650);
DISPLAY 1.234043 (-1750 3650);
PAINT GREEN (-1750 3650);
DISPLAY INVISIBLE (-1750 3650);
FORCEPROP 1 LAST HDL_TAP TRUE
J 2
(-2075 3575);
DISPLAY 1.234043 (-2075 3575);
PAINT GREEN (-2075 3575);
DISPLAY INVISIBLE (-2075 3575);
FORCEPROP 1 LAST PATH I68
J 2
(-1750 3700);
DISPLAY 0.936170 (-1750 3700);
PAINT GREEN (-1750 3700);
DISPLAY INVISIBLE (-1750 3700);
FORCEADD TAP..6
R 2
(-1750 3750);
FORCEPROP 3 LASTPIN (-1800 3750) SIG_NAME M_L_DQ<41>
J 0
(-1790 3760);
DISPLAY 0.659574 (-1790 3760);
PAINT MONO (-1790 3760);
DISPLAY INVISIBLE (-1790 3760);
FORCEPROP 1 LASTPIN (-1800 3750) BN 41
J 2
(-1750 3760);
DISPLAY 0.617021 (-1750 3760);
PAINT PINK (-1750 3760);
FORCEPROP 2 LAST CDS_LIB mstr_standard
J 2
(-1750 3750);
DISPLAY 0.787234 (-1750 3750);
PAINT MONO (-1750 3750);
DISPLAY INVISIBLE (-1750 3750);
FORCEPROP 1 LAST BODY_TYPE PLUMBING
J 2
(-1750 3700);
DISPLAY 1.234043 (-1750 3700);
PAINT GREEN (-1750 3700);
DISPLAY INVISIBLE (-1750 3700);
FORCEPROP 1 LAST HDL_TAP TRUE
J 2
(-2075 3625);
DISPLAY 1.234043 (-2075 3625);
PAINT GREEN (-2075 3625);
DISPLAY INVISIBLE (-2075 3625);
FORCEPROP 1 LAST PATH I69
J 2
(-1750 3750);
DISPLAY 0.936170 (-1750 3750);
PAINT GREEN (-1750 3750);
DISPLAY INVISIBLE (-1750 3750);
FORCEADD TAP..6
R 2
(900 4800);
FORCEPROP 3 LASTPIN (850 4800) SIG_NAME M_L_DQS_DN<14>
J 0
(860 4810);
DISPLAY 0.659574 (860 4810);
PAINT MONO (860 4810);
DISPLAY INVISIBLE (860 4810);
FORCEPROP 1 LASTPIN (850 4800) BN 14
J 2
(900 4810);
DISPLAY 0.617021 (900 4810);
PAINT PINK (900 4810);
FORCEPROP 2 LAST CDS_LIB mstr_standard
J 0
(900 4800);
DISPLAY 0.787234 (900 4800);
PAINT MONO (900 4800);
DISPLAY INVISIBLE (900 4800);
FORCEPROP 1 LAST BODY_TYPE PLUMBING
J 2
(900 4750);
DISPLAY 1.234043 (900 4750);
PAINT GREEN (900 4750);
DISPLAY INVISIBLE (900 4750);
FORCEPROP 1 LAST HDL_TAP TRUE
J 2
(575 4675);
DISPLAY 1.234043 (575 4675);
PAINT GREEN (575 4675);
DISPLAY INVISIBLE (575 4675);
FORCEPROP 1 LAST PATH I7
J 2
(900 4800);
DISPLAY 0.936170 (900 4800);
PAINT GREEN (900 4800);
DISPLAY INVISIBLE (900 4800);
FORCEADD TAP..6
R 2
(-1750 3850);
FORCEPROP 3 LASTPIN (-1800 3850) SIG_NAME M_L_DQ<43>
J 0
(-1790 3860);
DISPLAY 0.659574 (-1790 3860);
PAINT MONO (-1790 3860);
DISPLAY INVISIBLE (-1790 3860);
FORCEPROP 1 LASTPIN (-1800 3850) BN 43
J 2
(-1750 3860);
DISPLAY 0.617021 (-1750 3860);
PAINT PINK (-1750 3860);
FORCEPROP 2 LAST CDS_LIB mstr_standard
J 2
(-1750 3850);
DISPLAY 0.787234 (-1750 3850);
PAINT MONO (-1750 3850);
DISPLAY INVISIBLE (-1750 3850);
FORCEPROP 1 LAST BODY_TYPE PLUMBING
J 2
(-1750 3800);
DISPLAY 1.234043 (-1750 3800);
PAINT GREEN (-1750 3800);
DISPLAY INVISIBLE (-1750 3800);
FORCEPROP 1 LAST HDL_TAP TRUE
J 2
(-2075 3725);
DISPLAY 1.234043 (-2075 3725);
PAINT GREEN (-2075 3725);
DISPLAY INVISIBLE (-2075 3725);
FORCEPROP 1 LAST PATH I70
J 2
(-1750 3850);
DISPLAY 0.936170 (-1750 3850);
PAINT GREEN (-1750 3850);
DISPLAY INVISIBLE (-1750 3850);
FORCEADD TAP..6
R 2
(-1750 3900);
FORCEPROP 3 LASTPIN (-1800 3900) SIG_NAME M_L_DQ<42>
J 0
(-1790 3910);
DISPLAY 0.659574 (-1790 3910);
PAINT MONO (-1790 3910);
DISPLAY INVISIBLE (-1790 3910);
FORCEPROP 1 LASTPIN (-1800 3900) BN 42
J 2
(-1750 3910);
DISPLAY 0.617021 (-1750 3910);
PAINT PINK (-1750 3910);
FORCEPROP 2 LAST CDS_LIB mstr_standard
J 2
(-1750 3900);
DISPLAY 0.787234 (-1750 3900);
PAINT MONO (-1750 3900);
DISPLAY INVISIBLE (-1750 3900);
FORCEPROP 1 LAST BODY_TYPE PLUMBING
J 2
(-1750 3850);
DISPLAY 1.234043 (-1750 3850);
PAINT GREEN (-1750 3850);
DISPLAY INVISIBLE (-1750 3850);
FORCEPROP 1 LAST HDL_TAP TRUE
J 2
(-2075 3775);
DISPLAY 1.234043 (-2075 3775);
PAINT GREEN (-2075 3775);
DISPLAY INVISIBLE (-2075 3775);
FORCEPROP 1 LAST PATH I71
J 2
(-1750 3900);
DISPLAY 0.936170 (-1750 3900);
PAINT GREEN (-1750 3900);
DISPLAY INVISIBLE (-1750 3900);
FORCEADD TAP..6
R 2
(-1750 3500);
FORCEPROP 3 LASTPIN (-1800 3500) SIG_NAME M_L_DQ<34>
J 0
(-1790 3510);
DISPLAY 0.659574 (-1790 3510);
PAINT MONO (-1790 3510);
DISPLAY INVISIBLE (-1790 3510);
FORCEPROP 1 LASTPIN (-1800 3500) BN 34
J 2
(-1750 3510);
DISPLAY 0.617021 (-1750 3510);
PAINT PINK (-1750 3510);
FORCEPROP 2 LAST CDS_LIB mstr_standard
J 2
(-1750 3500);
DISPLAY 0.787234 (-1750 3500);
PAINT MONO (-1750 3500);
DISPLAY INVISIBLE (-1750 3500);
FORCEPROP 1 LAST BODY_TYPE PLUMBING
J 2
(-1750 3450);
DISPLAY 1.234043 (-1750 3450);
PAINT GREEN (-1750 3450);
DISPLAY INVISIBLE (-1750 3450);
FORCEPROP 1 LAST HDL_TAP TRUE
J 2
(-2075 3375);
DISPLAY 1.234043 (-2075 3375);
PAINT GREEN (-2075 3375);
DISPLAY INVISIBLE (-2075 3375);
FORCEPROP 1 LAST PATH I72
J 2
(-1750 3500);
DISPLAY 0.936170 (-1750 3500);
PAINT GREEN (-1750 3500);
DISPLAY INVISIBLE (-1750 3500);
FORCEADD TAP..6
R 2
(-1750 3450);
FORCEPROP 3 LASTPIN (-1800 3450) SIG_NAME M_L_DQ<35>
J 0
(-1790 3460);
DISPLAY 0.659574 (-1790 3460);
PAINT MONO (-1790 3460);
DISPLAY INVISIBLE (-1790 3460);
FORCEPROP 1 LASTPIN (-1800 3450) BN 35
J 2
(-1750 3460);
DISPLAY 0.617021 (-1750 3460);
PAINT PINK (-1750 3460);
FORCEPROP 2 LAST CDS_LIB mstr_standard
J 2
(-1750 3450);
DISPLAY 0.787234 (-1750 3450);
PAINT MONO (-1750 3450);
DISPLAY INVISIBLE (-1750 3450);
FORCEPROP 1 LAST BODY_TYPE PLUMBING
J 2
(-1750 3400);
DISPLAY 1.234043 (-1750 3400);
PAINT GREEN (-1750 3400);
DISPLAY INVISIBLE (-1750 3400);
FORCEPROP 1 LAST HDL_TAP TRUE
J 2
(-2075 3325);
DISPLAY 1.234043 (-2075 3325);
PAINT GREEN (-2075 3325);
DISPLAY INVISIBLE (-2075 3325);
FORCEPROP 1 LAST PATH I73
J 2
(-1750 3450);
DISPLAY 0.936170 (-1750 3450);
PAINT GREEN (-1750 3450);
DISPLAY INVISIBLE (-1750 3450);
FORCEADD TAP..6
R 2
(-1750 3550);
FORCEPROP 3 LASTPIN (-1800 3550) SIG_NAME M_L_DQ<37>
J 0
(-1790 3560);
DISPLAY 0.659574 (-1790 3560);
PAINT MONO (-1790 3560);
DISPLAY INVISIBLE (-1790 3560);
FORCEPROP 1 LASTPIN (-1800 3550) BN 37
J 2
(-1750 3560);
DISPLAY 0.617021 (-1750 3560);
PAINT PINK (-1750 3560);
FORCEPROP 2 LAST CDS_LIB mstr_standard
J 2
(-1750 3550);
DISPLAY 0.787234 (-1750 3550);
PAINT MONO (-1750 3550);
DISPLAY INVISIBLE (-1750 3550);
FORCEPROP 1 LAST BODY_TYPE PLUMBING
J 2
(-1750 3500);
DISPLAY 1.234043 (-1750 3500);
PAINT GREEN (-1750 3500);
DISPLAY INVISIBLE (-1750 3500);
FORCEPROP 1 LAST HDL_TAP TRUE
J 2
(-2075 3425);
DISPLAY 1.234043 (-2075 3425);
PAINT GREEN (-2075 3425);
DISPLAY INVISIBLE (-2075 3425);
FORCEPROP 1 LAST PATH I74
J 2
(-1750 3550);
DISPLAY 0.936170 (-1750 3550);
PAINT GREEN (-1750 3550);
DISPLAY INVISIBLE (-1750 3550);
FORCEADD TAP..6
R 2
(-1750 3600);
FORCEPROP 3 LASTPIN (-1800 3600) SIG_NAME M_L_DQ<36>
J 0
(-1790 3610);
DISPLAY 0.659574 (-1790 3610);
PAINT MONO (-1790 3610);
DISPLAY INVISIBLE (-1790 3610);
FORCEPROP 1 LASTPIN (-1800 3600) BN 36
J 2
(-1750 3610);
DISPLAY 0.617021 (-1750 3610);
PAINT PINK (-1750 3610);
FORCEPROP 2 LAST CDS_LIB mstr_standard
J 2
(-1750 3600);
DISPLAY 0.787234 (-1750 3600);
PAINT MONO (-1750 3600);
DISPLAY INVISIBLE (-1750 3600);
FORCEPROP 1 LAST BODY_TYPE PLUMBING
J 2
(-1750 3550);
DISPLAY 1.234043 (-1750 3550);
PAINT GREEN (-1750 3550);
DISPLAY INVISIBLE (-1750 3550);
FORCEPROP 1 LAST HDL_TAP TRUE
J 2
(-2075 3475);
DISPLAY 1.234043 (-2075 3475);
PAINT GREEN (-2075 3475);
DISPLAY INVISIBLE (-2075 3475);
FORCEPROP 1 LAST PATH I75
J 2
(-1750 3600);
DISPLAY 0.936170 (-1750 3600);
PAINT GREEN (-1750 3600);
DISPLAY INVISIBLE (-1750 3600);
FORCEADD TAP..6
R 2
(-1750 3650);
FORCEPROP 3 LASTPIN (-1800 3650) SIG_NAME M_L_DQ<39>
J 0
(-1790 3660);
DISPLAY 0.659574 (-1790 3660);
PAINT MONO (-1790 3660);
DISPLAY INVISIBLE (-1790 3660);
FORCEPROP 1 LASTPIN (-1800 3650) BN 39
J 2
(-1750 3660);
DISPLAY 0.617021 (-1750 3660);
PAINT PINK (-1750 3660);
FORCEPROP 2 LAST CDS_LIB mstr_standard
J 2
(-1750 3650);
DISPLAY 0.787234 (-1750 3650);
PAINT MONO (-1750 3650);
DISPLAY INVISIBLE (-1750 3650);
FORCEPROP 1 LAST BODY_TYPE PLUMBING
J 2
(-1750 3600);
DISPLAY 1.234043 (-1750 3600);
PAINT GREEN (-1750 3600);
DISPLAY INVISIBLE (-1750 3600);
FORCEPROP 1 LAST HDL_TAP TRUE
J 2
(-2075 3525);
DISPLAY 1.234043 (-2075 3525);
PAINT GREEN (-2075 3525);
DISPLAY INVISIBLE (-2075 3525);
FORCEPROP 1 LAST PATH I76
J 2
(-1750 3650);
DISPLAY 0.936170 (-1750 3650);
PAINT GREEN (-1750 3650);
DISPLAY INVISIBLE (-1750 3650);
FORCEADD TAP..6
R 2
(-1750 3250);
FORCEPROP 3 LASTPIN (-1800 3250) SIG_NAME M_L_DQ<31>
J 0
(-1790 3260);
DISPLAY 0.659574 (-1790 3260);
PAINT MONO (-1790 3260);
DISPLAY INVISIBLE (-1790 3260);
FORCEPROP 1 LASTPIN (-1800 3250) BN 31
J 2
(-1750 3260);
DISPLAY 0.617021 (-1750 3260);
PAINT PINK (-1750 3260);
FORCEPROP 2 LAST CDS_LIB mstr_standard
J 2
(-1750 3250);
DISPLAY 0.787234 (-1750 3250);
PAINT MONO (-1750 3250);
DISPLAY INVISIBLE (-1750 3250);
FORCEPROP 1 LAST BODY_TYPE PLUMBING
J 2
(-1750 3200);
DISPLAY 1.234043 (-1750 3200);
PAINT GREEN (-1750 3200);
DISPLAY INVISIBLE (-1750 3200);
FORCEPROP 1 LAST HDL_TAP TRUE
J 2
(-2075 3125);
DISPLAY 1.234043 (-2075 3125);
PAINT GREEN (-2075 3125);
DISPLAY INVISIBLE (-2075 3125);
FORCEPROP 1 LAST PATH I77
J 2
(-1750 3250);
DISPLAY 0.936170 (-1750 3250);
PAINT GREEN (-1750 3250);
DISPLAY INVISIBLE (-1750 3250);
FORCEADD TAP..6
R 2
(-1750 3300);
FORCEPROP 3 LASTPIN (-1800 3300) SIG_NAME M_L_DQ<30>
J 0
(-1790 3310);
DISPLAY 0.659574 (-1790 3310);
PAINT MONO (-1790 3310);
DISPLAY INVISIBLE (-1790 3310);
FORCEPROP 1 LASTPIN (-1800 3300) BN 30
J 2
(-1750 3310);
DISPLAY 0.617021 (-1750 3310);
PAINT PINK (-1750 3310);
FORCEPROP 2 LAST CDS_LIB mstr_standard
J 2
(-1750 3300);
DISPLAY 0.787234 (-1750 3300);
PAINT MONO (-1750 3300);
DISPLAY INVISIBLE (-1750 3300);
FORCEPROP 1 LAST BODY_TYPE PLUMBING
J 2
(-1750 3250);
DISPLAY 1.234043 (-1750 3250);
PAINT GREEN (-1750 3250);
DISPLAY INVISIBLE (-1750 3250);
FORCEPROP 1 LAST HDL_TAP TRUE
J 2
(-2075 3175);
DISPLAY 1.234043 (-2075 3175);
PAINT GREEN (-2075 3175);
DISPLAY INVISIBLE (-2075 3175);
FORCEPROP 1 LAST PATH I78
J 2
(-1750 3300);
DISPLAY 0.936170 (-1750 3300);
PAINT GREEN (-1750 3300);
DISPLAY INVISIBLE (-1750 3300);
FORCEADD TAP..6
R 2
(-1750 3200);
FORCEPROP 3 LASTPIN (-1800 3200) SIG_NAME M_L_DQ<28>
J 0
(-1790 3210);
DISPLAY 0.659574 (-1790 3210);
PAINT MONO (-1790 3210);
DISPLAY INVISIBLE (-1790 3210);
FORCEPROP 1 LASTPIN (-1800 3200) BN 28
J 2
(-1750 3210);
DISPLAY 0.617021 (-1750 3210);
PAINT PINK (-1750 3210);
FORCEPROP 2 LAST CDS_LIB mstr_standard
J 2
(-1750 3200);
DISPLAY 0.787234 (-1750 3200);
PAINT MONO (-1750 3200);
DISPLAY INVISIBLE (-1750 3200);
FORCEPROP 1 LAST BODY_TYPE PLUMBING
J 2
(-1750 3150);
DISPLAY 1.234043 (-1750 3150);
PAINT GREEN (-1750 3150);
DISPLAY INVISIBLE (-1750 3150);
FORCEPROP 1 LAST HDL_TAP TRUE
J 2
(-2075 3075);
DISPLAY 1.234043 (-2075 3075);
PAINT GREEN (-2075 3075);
DISPLAY INVISIBLE (-2075 3075);
FORCEPROP 1 LAST PATH I79
J 2
(-1750 3200);
DISPLAY 0.936170 (-1750 3200);
PAINT GREEN (-1750 3200);
DISPLAY INVISIBLE (-1750 3200);
FORCEADD TAP..6
R 2
(900 4700);
FORCEPROP 3 LASTPIN (850 4700) SIG_NAME M_L_DQS_DN<13>
J 0
(860 4710);
DISPLAY 0.659574 (860 4710);
PAINT MONO (860 4710);
DISPLAY INVISIBLE (860 4710);
FORCEPROP 1 LASTPIN (850 4700) BN 13
J 2
(900 4710);
DISPLAY 0.617021 (900 4710);
PAINT PINK (900 4710);
FORCEPROP 2 LAST CDS_LIB mstr_standard
J 0
(900 4700);
DISPLAY 0.787234 (900 4700);
PAINT MONO (900 4700);
DISPLAY INVISIBLE (900 4700);
FORCEPROP 1 LAST BODY_TYPE PLUMBING
J 2
(900 4650);
DISPLAY 1.234043 (900 4650);
PAINT GREEN (900 4650);
DISPLAY INVISIBLE (900 4650);
FORCEPROP 1 LAST HDL_TAP TRUE
J 2
(575 4575);
DISPLAY 1.234043 (575 4575);
PAINT GREEN (575 4575);
DISPLAY INVISIBLE (575 4575);
FORCEPROP 1 LAST PATH I8
J 2
(900 4700);
DISPLAY 0.936170 (900 4700);
PAINT GREEN (900 4700);
DISPLAY INVISIBLE (900 4700);
FORCEADD TAP..6
R 2
(-1750 3350);
FORCEPROP 3 LASTPIN (-1800 3350) SIG_NAME M_L_DQ<33>
J 0
(-1790 3360);
DISPLAY 0.659574 (-1790 3360);
PAINT MONO (-1790 3360);
DISPLAY INVISIBLE (-1790 3360);
FORCEPROP 1 LASTPIN (-1800 3350) BN 33
J 2
(-1750 3360);
DISPLAY 0.617021 (-1750 3360);
PAINT PINK (-1750 3360);
FORCEPROP 2 LAST CDS_LIB mstr_standard
J 2
(-1750 3350);
DISPLAY 0.787234 (-1750 3350);
PAINT MONO (-1750 3350);
DISPLAY INVISIBLE (-1750 3350);
FORCEPROP 1 LAST BODY_TYPE PLUMBING
J 2
(-1750 3300);
DISPLAY 1.234043 (-1750 3300);
PAINT GREEN (-1750 3300);
DISPLAY INVISIBLE (-1750 3300);
FORCEPROP 1 LAST HDL_TAP TRUE
J 2
(-2075 3225);
DISPLAY 1.234043 (-2075 3225);
PAINT GREEN (-2075 3225);
DISPLAY INVISIBLE (-2075 3225);
FORCEPROP 1 LAST PATH I80
J 2
(-1750 3350);
DISPLAY 0.936170 (-1750 3350);
PAINT GREEN (-1750 3350);
DISPLAY INVISIBLE (-1750 3350);
FORCEADD TAP..6
R 2
(-1750 3400);
FORCEPROP 3 LASTPIN (-1800 3400) SIG_NAME M_L_DQ<32>
J 0
(-1790 3410);
DISPLAY 0.659574 (-1790 3410);
PAINT MONO (-1790 3410);
DISPLAY INVISIBLE (-1790 3410);
FORCEPROP 1 LASTPIN (-1800 3400) BN 32
J 2
(-1750 3410);
DISPLAY 0.617021 (-1750 3410);
PAINT PINK (-1750 3410);
FORCEPROP 2 LAST CDS_LIB mstr_standard
J 2
(-1750 3400);
DISPLAY 0.787234 (-1750 3400);
PAINT MONO (-1750 3400);
DISPLAY INVISIBLE (-1750 3400);
FORCEPROP 1 LAST BODY_TYPE PLUMBING
J 2
(-1750 3350);
DISPLAY 1.234043 (-1750 3350);
PAINT GREEN (-1750 3350);
DISPLAY INVISIBLE (-1750 3350);
FORCEPROP 1 LAST HDL_TAP TRUE
J 2
(-2075 3275);
DISPLAY 1.234043 (-2075 3275);
PAINT GREEN (-2075 3275);
DISPLAY INVISIBLE (-2075 3275);
FORCEPROP 1 LAST PATH I81
J 2
(-1750 3400);
DISPLAY 0.936170 (-1750 3400);
PAINT GREEN (-1750 3400);
DISPLAY INVISIBLE (-1750 3400);
FORCEADD TAP..6
R 2
(-1750 3000);
FORCEPROP 3 LASTPIN (-1800 3000) SIG_NAME M_L_DQ<24>
J 0
(-1790 3010);
DISPLAY 0.659574 (-1790 3010);
PAINT MONO (-1790 3010);
DISPLAY INVISIBLE (-1790 3010);
FORCEPROP 1 LASTPIN (-1800 3000) BN 24
J 2
(-1750 3010);
DISPLAY 0.617021 (-1750 3010);
PAINT PINK (-1750 3010);
FORCEPROP 2 LAST CDS_LIB mstr_standard
J 2
(-1750 3000);
DISPLAY 0.787234 (-1750 3000);
PAINT MONO (-1750 3000);
DISPLAY INVISIBLE (-1750 3000);
FORCEPROP 1 LAST BODY_TYPE PLUMBING
J 2
(-1750 2950);
DISPLAY 1.234043 (-1750 2950);
PAINT GREEN (-1750 2950);
DISPLAY INVISIBLE (-1750 2950);
FORCEPROP 1 LAST HDL_TAP TRUE
J 2
(-2075 2875);
DISPLAY 1.234043 (-2075 2875);
PAINT GREEN (-2075 2875);
DISPLAY INVISIBLE (-2075 2875);
FORCEPROP 1 LAST PATH I82
J 2
(-1750 3000);
DISPLAY 0.936170 (-1750 3000);
PAINT GREEN (-1750 3000);
DISPLAY INVISIBLE (-1750 3000);
FORCEADD TAP..6
R 2
(-1750 2950);
FORCEPROP 3 LASTPIN (-1800 2950) SIG_NAME M_L_DQ<25>
J 0
(-1790 2960);
DISPLAY 0.659574 (-1790 2960);
PAINT MONO (-1790 2960);
DISPLAY INVISIBLE (-1790 2960);
FORCEPROP 1 LASTPIN (-1800 2950) BN 25
J 2
(-1750 2960);
DISPLAY 0.617021 (-1750 2960);
PAINT PINK (-1750 2960);
FORCEPROP 2 LAST CDS_LIB mstr_standard
J 2
(-1750 2950);
DISPLAY 0.787234 (-1750 2950);
PAINT MONO (-1750 2950);
DISPLAY INVISIBLE (-1750 2950);
FORCEPROP 1 LAST BODY_TYPE PLUMBING
J 2
(-1750 2900);
DISPLAY 1.234043 (-1750 2900);
PAINT GREEN (-1750 2900);
DISPLAY INVISIBLE (-1750 2900);
FORCEPROP 1 LAST HDL_TAP TRUE
J 2
(-2075 2825);
DISPLAY 1.234043 (-2075 2825);
PAINT GREEN (-2075 2825);
DISPLAY INVISIBLE (-2075 2825);
FORCEPROP 1 LAST PATH I83
J 2
(-1750 2950);
DISPLAY 0.936170 (-1750 2950);
PAINT GREEN (-1750 2950);
DISPLAY INVISIBLE (-1750 2950);
FORCEADD TAP..6
R 2
(-1750 3050);
FORCEPROP 3 LASTPIN (-1800 3050) SIG_NAME M_L_DQ<27>
J 0
(-1790 3060);
DISPLAY 0.659574 (-1790 3060);
PAINT MONO (-1790 3060);
DISPLAY INVISIBLE (-1790 3060);
FORCEPROP 1 LASTPIN (-1800 3050) BN 27
J 2
(-1750 3060);
DISPLAY 0.617021 (-1750 3060);
PAINT PINK (-1750 3060);
FORCEPROP 2 LAST CDS_LIB mstr_standard
J 2
(-1750 3050);
DISPLAY 0.787234 (-1750 3050);
PAINT MONO (-1750 3050);
DISPLAY INVISIBLE (-1750 3050);
FORCEPROP 1 LAST BODY_TYPE PLUMBING
J 2
(-1750 3000);
DISPLAY 1.234043 (-1750 3000);
PAINT GREEN (-1750 3000);
DISPLAY INVISIBLE (-1750 3000);
FORCEPROP 1 LAST HDL_TAP TRUE
J 2
(-2075 2925);
DISPLAY 1.234043 (-2075 2925);
PAINT GREEN (-2075 2925);
DISPLAY INVISIBLE (-2075 2925);
FORCEPROP 1 LAST PATH I84
J 2
(-1750 3050);
DISPLAY 0.936170 (-1750 3050);
PAINT GREEN (-1750 3050);
DISPLAY INVISIBLE (-1750 3050);
FORCEADD TAP..6
R 2
(-1750 3150);
FORCEPROP 3 LASTPIN (-1800 3150) SIG_NAME M_L_DQ<29>
J 0
(-1790 3160);
DISPLAY 0.659574 (-1790 3160);
PAINT MONO (-1790 3160);
DISPLAY INVISIBLE (-1790 3160);
FORCEPROP 1 LASTPIN (-1800 3150) BN 29
J 2
(-1750 3160);
DISPLAY 0.617021 (-1750 3160);
PAINT PINK (-1750 3160);
FORCEPROP 2 LAST CDS_LIB mstr_standard
J 2
(-1750 3150);
DISPLAY 0.787234 (-1750 3150);
PAINT MONO (-1750 3150);
DISPLAY INVISIBLE (-1750 3150);
FORCEPROP 1 LAST BODY_TYPE PLUMBING
J 2
(-1750 3100);
DISPLAY 1.234043 (-1750 3100);
PAINT GREEN (-1750 3100);
DISPLAY INVISIBLE (-1750 3100);
FORCEPROP 1 LAST HDL_TAP TRUE
J 2
(-2075 3025);
DISPLAY 1.234043 (-2075 3025);
PAINT GREEN (-2075 3025);
DISPLAY INVISIBLE (-2075 3025);
FORCEPROP 1 LAST PATH I85
J 2
(-1750 3150);
DISPLAY 0.936170 (-1750 3150);
PAINT GREEN (-1750 3150);
DISPLAY INVISIBLE (-1750 3150);
FORCEADD TAP..6
R 2
(-1750 3100);
FORCEPROP 3 LASTPIN (-1800 3100) SIG_NAME M_L_DQ<26>
J 0
(-1790 3110);
DISPLAY 0.659574 (-1790 3110);
PAINT MONO (-1790 3110);
DISPLAY INVISIBLE (-1790 3110);
FORCEPROP 1 LASTPIN (-1800 3100) BN 26
J 2
(-1750 3110);
DISPLAY 0.617021 (-1750 3110);
PAINT PINK (-1750 3110);
FORCEPROP 2 LAST CDS_LIB mstr_standard
J 2
(-1750 3100);
DISPLAY 0.787234 (-1750 3100);
PAINT MONO (-1750 3100);
DISPLAY INVISIBLE (-1750 3100);
FORCEPROP 1 LAST BODY_TYPE PLUMBING
J 2
(-1750 3050);
DISPLAY 1.234043 (-1750 3050);
PAINT GREEN (-1750 3050);
DISPLAY INVISIBLE (-1750 3050);
FORCEPROP 1 LAST HDL_TAP TRUE
J 2
(-2075 2975);
DISPLAY 1.234043 (-2075 2975);
PAINT GREEN (-2075 2975);
DISPLAY INVISIBLE (-2075 2975);
FORCEPROP 1 LAST PATH I86
J 2
(-1750 3100);
DISPLAY 0.936170 (-1750 3100);
PAINT GREEN (-1750 3100);
DISPLAY INVISIBLE (-1750 3100);
FORCEADD TAP..6
R 2
(-1750 2700);
FORCEPROP 3 LASTPIN (-1800 2700) SIG_NAME M_L_DQ<18>
J 0
(-1790 2710);
DISPLAY 0.659574 (-1790 2710);
PAINT MONO (-1790 2710);
DISPLAY INVISIBLE (-1790 2710);
FORCEPROP 1 LASTPIN (-1800 2700) BN 18
J 2
(-1750 2710);
DISPLAY 0.617021 (-1750 2710);
PAINT PINK (-1750 2710);
FORCEPROP 2 LAST CDS_LIB mstr_standard
J 2
(-1750 2700);
DISPLAY 0.787234 (-1750 2700);
PAINT MONO (-1750 2700);
DISPLAY INVISIBLE (-1750 2700);
FORCEPROP 1 LAST BODY_TYPE PLUMBING
J 2
(-1750 2650);
DISPLAY 1.234043 (-1750 2650);
PAINT GREEN (-1750 2650);
DISPLAY INVISIBLE (-1750 2650);
FORCEPROP 1 LAST HDL_TAP TRUE
J 2
(-2075 2575);
DISPLAY 1.234043 (-2075 2575);
PAINT GREEN (-2075 2575);
DISPLAY INVISIBLE (-2075 2575);
FORCEPROP 1 LAST PATH I87
J 2
(-1750 2700);
DISPLAY 0.936170 (-1750 2700);
PAINT GREEN (-1750 2700);
DISPLAY INVISIBLE (-1750 2700);
FORCEADD TAP..6
R 2
(-1750 2750);
FORCEPROP 3 LASTPIN (-1800 2750) SIG_NAME M_L_DQ<21>
J 0
(-1790 2760);
DISPLAY 0.659574 (-1790 2760);
PAINT MONO (-1790 2760);
DISPLAY INVISIBLE (-1790 2760);
FORCEPROP 1 LASTPIN (-1800 2750) BN 21
J 2
(-1750 2760);
DISPLAY 0.617021 (-1750 2760);
PAINT PINK (-1750 2760);
FORCEPROP 2 LAST CDS_LIB mstr_standard
J 2
(-1750 2750);
DISPLAY 0.787234 (-1750 2750);
PAINT MONO (-1750 2750);
DISPLAY INVISIBLE (-1750 2750);
FORCEPROP 1 LAST BODY_TYPE PLUMBING
J 2
(-1750 2700);
DISPLAY 1.234043 (-1750 2700);
PAINT GREEN (-1750 2700);
DISPLAY INVISIBLE (-1750 2700);
FORCEPROP 1 LAST HDL_TAP TRUE
J 2
(-2075 2625);
DISPLAY 1.234043 (-2075 2625);
PAINT GREEN (-2075 2625);
DISPLAY INVISIBLE (-2075 2625);
FORCEPROP 1 LAST PATH I88
J 2
(-1750 2750);
DISPLAY 0.936170 (-1750 2750);
PAINT GREEN (-1750 2750);
DISPLAY INVISIBLE (-1750 2750);
FORCEADD TAP..6
R 2
(-1750 2800);
FORCEPROP 3 LASTPIN (-1800 2800) SIG_NAME M_L_DQ<20>
J 0
(-1790 2810);
DISPLAY 0.659574 (-1790 2810);
PAINT MONO (-1790 2810);
DISPLAY INVISIBLE (-1790 2810);
FORCEPROP 1 LASTPIN (-1800 2800) BN 20
J 2
(-1750 2810);
DISPLAY 0.617021 (-1750 2810);
PAINT PINK (-1750 2810);
FORCEPROP 2 LAST CDS_LIB mstr_standard
J 2
(-1750 2800);
DISPLAY 0.787234 (-1750 2800);
PAINT MONO (-1750 2800);
DISPLAY INVISIBLE (-1750 2800);
FORCEPROP 1 LAST BODY_TYPE PLUMBING
J 2
(-1750 2750);
DISPLAY 1.234043 (-1750 2750);
PAINT GREEN (-1750 2750);
DISPLAY INVISIBLE (-1750 2750);
FORCEPROP 1 LAST HDL_TAP TRUE
J 2
(-2075 2675);
DISPLAY 1.234043 (-2075 2675);
PAINT GREEN (-2075 2675);
DISPLAY INVISIBLE (-2075 2675);
FORCEPROP 1 LAST PATH I89
J 2
(-1750 2800);
DISPLAY 0.936170 (-1750 2800);
PAINT GREEN (-1750 2800);
DISPLAY INVISIBLE (-1750 2800);
FORCEADD TAP..6
R 2
(900 4600);
FORCEPROP 3 LASTPIN (850 4600) SIG_NAME M_L_DQS_DN<12>
J 0
(860 4610);
DISPLAY 0.659574 (860 4610);
PAINT MONO (860 4610);
DISPLAY INVISIBLE (860 4610);
FORCEPROP 1 LASTPIN (850 4600) BN 12
J 2
(900 4610);
DISPLAY 0.617021 (900 4610);
PAINT PINK (900 4610);
FORCEPROP 2 LAST CDS_LIB mstr_standard
J 0
(900 4600);
DISPLAY 0.787234 (900 4600);
PAINT MONO (900 4600);
DISPLAY INVISIBLE (900 4600);
FORCEPROP 1 LAST BODY_TYPE PLUMBING
J 2
(900 4550);
DISPLAY 1.234043 (900 4550);
PAINT GREEN (900 4550);
DISPLAY INVISIBLE (900 4550);
FORCEPROP 1 LAST HDL_TAP TRUE
J 2
(575 4475);
DISPLAY 1.234043 (575 4475);
PAINT GREEN (575 4475);
DISPLAY INVISIBLE (575 4475);
FORCEPROP 1 LAST PATH I9
J 2
(900 4600);
DISPLAY 0.936170 (900 4600);
PAINT GREEN (900 4600);
DISPLAY INVISIBLE (900 4600);
FORCEADD TAP..6
R 2
(-1750 2900);
FORCEPROP 3 LASTPIN (-1800 2900) SIG_NAME M_L_DQ<22>
J 0
(-1790 2910);
DISPLAY 0.659574 (-1790 2910);
PAINT MONO (-1790 2910);
DISPLAY INVISIBLE (-1790 2910);
FORCEPROP 1 LASTPIN (-1800 2900) BN 22
J 2
(-1750 2910);
DISPLAY 0.617021 (-1750 2910);
PAINT PINK (-1750 2910);
FORCEPROP 2 LAST CDS_LIB mstr_standard
J 2
(-1750 2900);
DISPLAY 0.787234 (-1750 2900);
PAINT MONO (-1750 2900);
DISPLAY INVISIBLE (-1750 2900);
FORCEPROP 1 LAST BODY_TYPE PLUMBING
J 2
(-1750 2850);
DISPLAY 1.234043 (-1750 2850);
PAINT GREEN (-1750 2850);
DISPLAY INVISIBLE (-1750 2850);
FORCEPROP 1 LAST HDL_TAP TRUE
J 2
(-2075 2775);
DISPLAY 1.234043 (-2075 2775);
PAINT GREEN (-2075 2775);
DISPLAY INVISIBLE (-2075 2775);
FORCEPROP 1 LAST PATH I90
J 2
(-1750 2900);
DISPLAY 0.936170 (-1750 2900);
PAINT GREEN (-1750 2900);
DISPLAY INVISIBLE (-1750 2900);
FORCEADD TAP..6
R 2
(-1750 2850);
FORCEPROP 3 LASTPIN (-1800 2850) SIG_NAME M_L_DQ<23>
J 0
(-1790 2860);
DISPLAY 0.659574 (-1790 2860);
PAINT MONO (-1790 2860);
DISPLAY INVISIBLE (-1790 2860);
FORCEPROP 1 LASTPIN (-1800 2850) BN 23
J 2
(-1750 2860);
DISPLAY 0.617021 (-1750 2860);
PAINT PINK (-1750 2860);
FORCEPROP 2 LAST CDS_LIB mstr_standard
J 2
(-1750 2850);
DISPLAY 0.787234 (-1750 2850);
PAINT MONO (-1750 2850);
DISPLAY INVISIBLE (-1750 2850);
FORCEPROP 1 LAST BODY_TYPE PLUMBING
J 2
(-1750 2800);
DISPLAY 1.234043 (-1750 2800);
PAINT GREEN (-1750 2800);
DISPLAY INVISIBLE (-1750 2800);
FORCEPROP 1 LAST HDL_TAP TRUE
J 2
(-2075 2725);
DISPLAY 1.234043 (-2075 2725);
PAINT GREEN (-2075 2725);
DISPLAY INVISIBLE (-2075 2725);
FORCEPROP 1 LAST PATH I91
J 2
(-1750 2850);
DISPLAY 0.936170 (-1750 2850);
PAINT GREEN (-1750 2850);
DISPLAY INVISIBLE (-1750 2850);
FORCEADD TAP..6
R 2
(-1750 2450);
FORCEPROP 3 LASTPIN (-1800 2450) SIG_NAME M_L_DQ<15>
J 0
(-1790 2460);
DISPLAY 0.659574 (-1790 2460);
PAINT MONO (-1790 2460);
DISPLAY INVISIBLE (-1790 2460);
FORCEPROP 1 LASTPIN (-1800 2450) BN 15
J 2
(-1750 2460);
DISPLAY 0.617021 (-1750 2460);
PAINT PINK (-1750 2460);
FORCEPROP 2 LAST CDS_LIB mstr_standard
J 2
(-1750 2450);
DISPLAY 0.787234 (-1750 2450);
PAINT MONO (-1750 2450);
DISPLAY INVISIBLE (-1750 2450);
FORCEPROP 1 LAST BODY_TYPE PLUMBING
J 2
(-1750 2400);
DISPLAY 1.234043 (-1750 2400);
PAINT GREEN (-1750 2400);
DISPLAY INVISIBLE (-1750 2400);
FORCEPROP 1 LAST HDL_TAP TRUE
J 2
(-2075 2325);
DISPLAY 1.234043 (-2075 2325);
PAINT GREEN (-2075 2325);
DISPLAY INVISIBLE (-2075 2325);
FORCEPROP 1 LAST PATH I92
J 2
(-1750 2450);
DISPLAY 0.936170 (-1750 2450);
PAINT GREEN (-1750 2450);
DISPLAY INVISIBLE (-1750 2450);
FORCEADD TAP..6
R 2
(-1750 2500);
FORCEPROP 3 LASTPIN (-1800 2500) SIG_NAME M_L_DQ<14>
J 0
(-1790 2510);
DISPLAY 0.659574 (-1790 2510);
PAINT MONO (-1790 2510);
DISPLAY INVISIBLE (-1790 2510);
FORCEPROP 1 LASTPIN (-1800 2500) BN 14
J 2
(-1750 2510);
DISPLAY 0.617021 (-1750 2510);
PAINT PINK (-1750 2510);
FORCEPROP 2 LAST CDS_LIB mstr_standard
J 2
(-1750 2500);
DISPLAY 0.787234 (-1750 2500);
PAINT MONO (-1750 2500);
DISPLAY INVISIBLE (-1750 2500);
FORCEPROP 1 LAST BODY_TYPE PLUMBING
J 2
(-1750 2450);
DISPLAY 1.234043 (-1750 2450);
PAINT GREEN (-1750 2450);
DISPLAY INVISIBLE (-1750 2450);
FORCEPROP 1 LAST HDL_TAP TRUE
J 2
(-2075 2375);
DISPLAY 1.234043 (-2075 2375);
PAINT GREEN (-2075 2375);
DISPLAY INVISIBLE (-2075 2375);
FORCEPROP 1 LAST PATH I93
J 2
(-1750 2500);
DISPLAY 0.936170 (-1750 2500);
PAINT GREEN (-1750 2500);
DISPLAY INVISIBLE (-1750 2500);
FORCEADD TAP..6
R 2
(-1750 2600);
FORCEPROP 3 LASTPIN (-1800 2600) SIG_NAME M_L_DQ<16>
J 0
(-1790 2610);
DISPLAY 0.659574 (-1790 2610);
PAINT MONO (-1790 2610);
DISPLAY INVISIBLE (-1790 2610);
FORCEPROP 1 LASTPIN (-1800 2600) BN 16
J 2
(-1750 2610);
DISPLAY 0.617021 (-1750 2610);
PAINT PINK (-1750 2610);
FORCEPROP 2 LAST CDS_LIB mstr_standard
J 2
(-1750 2600);
DISPLAY 0.787234 (-1750 2600);
PAINT MONO (-1750 2600);
DISPLAY INVISIBLE (-1750 2600);
FORCEPROP 1 LAST BODY_TYPE PLUMBING
J 2
(-1750 2550);
DISPLAY 1.234043 (-1750 2550);
PAINT GREEN (-1750 2550);
DISPLAY INVISIBLE (-1750 2550);
FORCEPROP 1 LAST HDL_TAP TRUE
J 2
(-2075 2475);
DISPLAY 1.234043 (-2075 2475);
PAINT GREEN (-2075 2475);
DISPLAY INVISIBLE (-2075 2475);
FORCEPROP 1 LAST PATH I94
J 2
(-1750 2600);
DISPLAY 0.936170 (-1750 2600);
PAINT GREEN (-1750 2600);
DISPLAY INVISIBLE (-1750 2600);
FORCEADD TAP..6
R 2
(-1750 2550);
FORCEPROP 3 LASTPIN (-1800 2550) SIG_NAME M_L_DQ<17>
J 0
(-1790 2560);
DISPLAY 0.659574 (-1790 2560);
PAINT MONO (-1790 2560);
DISPLAY INVISIBLE (-1790 2560);
FORCEPROP 1 LASTPIN (-1800 2550) BN 17
J 2
(-1750 2560);
DISPLAY 0.617021 (-1750 2560);
PAINT PINK (-1750 2560);
FORCEPROP 2 LAST CDS_LIB mstr_standard
J 2
(-1750 2550);
DISPLAY 0.787234 (-1750 2550);
PAINT MONO (-1750 2550);
DISPLAY INVISIBLE (-1750 2550);
FORCEPROP 1 LAST BODY_TYPE PLUMBING
J 2
(-1750 2500);
DISPLAY 1.234043 (-1750 2500);
PAINT GREEN (-1750 2500);
DISPLAY INVISIBLE (-1750 2500);
FORCEPROP 1 LAST HDL_TAP TRUE
J 2
(-2075 2425);
DISPLAY 1.234043 (-2075 2425);
PAINT GREEN (-2075 2425);
DISPLAY INVISIBLE (-2075 2425);
FORCEPROP 1 LAST PATH I95
J 2
(-1750 2550);
DISPLAY 0.936170 (-1750 2550);
PAINT GREEN (-1750 2550);
DISPLAY INVISIBLE (-1750 2550);
FORCEADD TAP..6
R 2
(-1750 2650);
FORCEPROP 3 LASTPIN (-1800 2650) SIG_NAME M_L_DQ<19>
J 0
(-1790 2660);
DISPLAY 0.659574 (-1790 2660);
PAINT MONO (-1790 2660);
DISPLAY INVISIBLE (-1790 2660);
FORCEPROP 1 LASTPIN (-1800 2650) BN 19
J 2
(-1750 2660);
DISPLAY 0.617021 (-1750 2660);
PAINT PINK (-1750 2660);
FORCEPROP 2 LAST CDS_LIB mstr_standard
J 2
(-1750 2650);
DISPLAY 0.787234 (-1750 2650);
PAINT MONO (-1750 2650);
DISPLAY INVISIBLE (-1750 2650);
FORCEPROP 1 LAST BODY_TYPE PLUMBING
J 2
(-1750 2600);
DISPLAY 1.234043 (-1750 2600);
PAINT GREEN (-1750 2600);
DISPLAY INVISIBLE (-1750 2600);
FORCEPROP 1 LAST HDL_TAP TRUE
J 2
(-2075 2525);
DISPLAY 1.234043 (-2075 2525);
PAINT GREEN (-2075 2525);
DISPLAY INVISIBLE (-2075 2525);
FORCEPROP 1 LAST PATH I96
J 2
(-1750 2650);
DISPLAY 0.936170 (-1750 2650);
PAINT GREEN (-1750 2650);
DISPLAY INVISIBLE (-1750 2650);
FORCEADD TAP..6
R 2
(-1750 2400);
FORCEPROP 3 LASTPIN (-1800 2400) SIG_NAME M_L_DQ<12>
J 0
(-1790 2410);
DISPLAY 0.659574 (-1790 2410);
PAINT MONO (-1790 2410);
DISPLAY INVISIBLE (-1790 2410);
FORCEPROP 1 LASTPIN (-1800 2400) BN 12
J 2
(-1750 2410);
DISPLAY 0.617021 (-1750 2410);
PAINT PINK (-1750 2410);
FORCEPROP 2 LAST CDS_LIB mstr_standard
J 2
(-1750 2400);
DISPLAY 0.787234 (-1750 2400);
PAINT MONO (-1750 2400);
DISPLAY INVISIBLE (-1750 2400);
FORCEPROP 1 LAST BODY_TYPE PLUMBING
J 2
(-1750 2350);
DISPLAY 1.234043 (-1750 2350);
PAINT GREEN (-1750 2350);
DISPLAY INVISIBLE (-1750 2350);
FORCEPROP 1 LAST HDL_TAP TRUE
J 2
(-2075 2275);
DISPLAY 1.234043 (-2075 2275);
PAINT GREEN (-2075 2275);
DISPLAY INVISIBLE (-2075 2275);
FORCEPROP 1 LAST PATH I97
J 2
(-1750 2400);
DISPLAY 0.936170 (-1750 2400);
PAINT GREEN (-1750 2400);
DISPLAY INVISIBLE (-1750 2400);
FORCEADD TAP..6
R 2
(-1750 2300);
FORCEPROP 3 LASTPIN (-1800 2300) SIG_NAME M_L_DQ<10>
J 0
(-1790 2310);
DISPLAY 0.659574 (-1790 2310);
PAINT MONO (-1790 2310);
DISPLAY INVISIBLE (-1790 2310);
FORCEPROP 1 LASTPIN (-1800 2300) BN 10
J 2
(-1750 2310);
DISPLAY 0.617021 (-1750 2310);
PAINT PINK (-1750 2310);
FORCEPROP 2 LAST CDS_LIB mstr_standard
J 2
(-1750 2300);
DISPLAY 0.787234 (-1750 2300);
PAINT MONO (-1750 2300);
DISPLAY INVISIBLE (-1750 2300);
FORCEPROP 1 LAST BODY_TYPE PLUMBING
J 2
(-1750 2250);
DISPLAY 1.234043 (-1750 2250);
PAINT GREEN (-1750 2250);
DISPLAY INVISIBLE (-1750 2250);
FORCEPROP 1 LAST HDL_TAP TRUE
J 2
(-2075 2175);
DISPLAY 1.234043 (-2075 2175);
PAINT GREEN (-2075 2175);
DISPLAY INVISIBLE (-2075 2175);
FORCEPROP 1 LAST PATH I98
J 2
(-1750 2300);
DISPLAY 0.936170 (-1750 2300);
PAINT GREEN (-1750 2300);
DISPLAY INVISIBLE (-1750 2300);
FORCEADD TAP..6
R 2
(-1750 2350);
FORCEPROP 3 LASTPIN (-1800 2350) SIG_NAME M_L_DQ<13>
J 0
(-1790 2360);
DISPLAY 0.659574 (-1790 2360);
PAINT MONO (-1790 2360);
DISPLAY INVISIBLE (-1790 2360);
FORCEPROP 1 LASTPIN (-1800 2350) BN 13
J 2
(-1750 2360);
DISPLAY 0.617021 (-1750 2360);
PAINT PINK (-1750 2360);
FORCEPROP 2 LAST CDS_LIB mstr_standard
J 2
(-1750 2350);
DISPLAY 0.787234 (-1750 2350);
PAINT MONO (-1750 2350);
DISPLAY INVISIBLE (-1750 2350);
FORCEPROP 1 LAST BODY_TYPE PLUMBING
J 2
(-1750 2300);
DISPLAY 1.234043 (-1750 2300);
PAINT GREEN (-1750 2300);
DISPLAY INVISIBLE (-1750 2300);
FORCEPROP 1 LAST HDL_TAP TRUE
J 2
(-2075 2225);
DISPLAY 1.234043 (-2075 2225);
PAINT GREEN (-2075 2225);
DISPLAY INVISIBLE (-2075 2225);
FORCEPROP 1 LAST PATH I99
J 2
(-1750 2350);
DISPLAY 0.936170 (-1750 2350);
PAINT GREEN (-1750 2350);
DISPLAY INVISIBLE (-1750 2350);
FORCEADD INTEL_CORP_BPAGE..1
(2650 500);
FORCEPROP 1 LAST CDS_CON_LAST_MODIFIED Fri Jun 16 17:48:32 2017
J 0
(1225 825);
DISPLAY 0.787234 (1225 825);
PAINT ORANGE (1225 825);
DISPLAY INVISIBLE (1225 825);
FORCEPROP 1 LAST CUSTOM_TXT_CDS <CURRENT_DESIGN_SHEET> OF <TOTAL_DESIGN_SHEETS>
J 0
(2150 525);
PAINT ORANGE (2150 525);
FORCEPROP 2 LAST CUSTOM_TXT_CDS <XR_PAGE_TITLE>
J 0
(-5240 5750);
DISPLAY 0.638298 (-5240 5750);
PAINT PINK (-5240 5750);
DISPLAY INVISIBLE (-5240 5750);
FORCEPROP 2 LAST CUSTOM_TXT_CDS <CON_LAST_MODIFIED>
J 0
(-1350 575);
DISPLAY 1.297872 (-1350 575);
PAINT ORANGE (-1350 575);
FORCEPROP 1 LAST SCH_TITLE CPU1 DDR4 CH L DIMM0
J 0
(-5300 550);
DISPLAY 1.212766 (-5300 550);
PAINT WHITE (-5300 550);
FORCEPROP 2 LAST PAGE_BORDER TRUE
J 0
(-5240 5750);
DISPLAY 0.680851 (-5240 5750);
PAINT PINK (-5240 5750);
DISPLAY INVISIBLE (-5240 5750);
FORCEPROP 2 LAST CDS_LIB mstr_symbols
J 0
(2650 500);
DISPLAY 0.787234 (2650 500);
PAINT MONO (2650 500);
DISPLAY INVISIBLE (2650 500);
FORCEPROP 1 LAST COMMENT_BODY TRUE
J 0
(2660 510);
DISPLAY 0.382979 (2660 510);
PAINT GREEN (2660 510);
DISPLAY INVISIBLE (2660 510);
FORCEPROP 2 LAST CDS_XR_PAGE_TITLE CR-85 : @BASEBOARD_FAB2_LIB.BASEBOARD_FAB2(SCH_1):PAGE85
J 0
(-5240 5750);
DISPLAY 0.638298 (-5240 5750);
PAINT PINK (-5240 5750);
DISPLAY INVISIBLE (-5240 5750);
FORCEADD BOM_NOTE..1
(-5000 5275);
FORCEPROP 0 LAST L1 STUFF FOR SKU A & B
J 0
(-5150 5175);
DISPLAY 1.063830 (-5150 5175);
PAINT WHITE (-5150 5175);
FORCEPROP 2 LAST CDS_LIB mstr_symbols
J 0
(-5000 5275);
PAINT ORANGE (-5000 5275);
DISPLAY INVISIBLE (-5000 5275);
FORCEPROP 2 LAST BOM_COST SB
J 0
(-5150 5250);
DISPLAY 1.361702 (-5150 5250);
PAINT ORANGE (-5150 5250);
DISPLAY INVISIBLE (-5150 5250);
FORCEPROP 1 LAST COMMENT_BODY TRUE
J 0
(-4975 5375);
DISPLAY 1.319149 (-4975 5375);
PAINT ORANGE (-4975 5375);
DISPLAY INVISIBLE (-4975 5375);
FORCEPROP 2 LAST ROOM SB_HEADERS
J 0
(-5150 5250);
DISPLAY 1.361702 (-5150 5250);
PAINT ORANGE (-5150 5250);
DISPLAY INVISIBLE (-5150 5250);
WIRE 16 -1 (-1350 2575)(-1350 2450);
WIRE 16 -1 (-1350 2450)(-950 2450);
WIRE 16 -1 (-950 2400)(-950 2450);
WIRE 16 -1 (-950 2450)(-750 2450);
WIRE 16 -1 (-950 2350)(-950 2400);
WIRE 16 -1 (-950 2400)(-750 2400);
WIRE 16 -1 (-950 2300)(-950 2350);
WIRE 16 -1 (-950 2350)(-750 2350);
WIRE 16 -1 (-950 2250)(-950 2300);
WIRE 16 -1 (-950 2300)(-750 2300);
WIRE 16 -1 (-950 2200)(-950 2250);
WIRE 16 -1 (-950 2250)(-750 2250);
WIRE 16 -1 (-950 2150)(-950 2200);
WIRE 16 -1 (-950 2200)(-750 2200);
WIRE 16 -1 (-950 2100)(-950 2150);
WIRE 16 -1 (-950 2150)(-750 2150);
WIRE 16 -1 (-950 2050)(-950 2100);
WIRE 16 -1 (-950 2100)(-750 2100);
WIRE 16 -1 (-950 2000)(-950 2050);
WIRE 16 -1 (-950 2050)(-750 2050);
WIRE 16 -1 (-950 1950)(-950 2000);
WIRE 16 -1 (-950 2000)(-750 2000);
WIRE 16 -1 (-950 1900)(-950 1950);
WIRE 16 -1 (-950 1950)(-750 1950);
WIRE 16 -1 (-950 1850)(-950 1900);
WIRE 16 -1 (-950 1900)(-750 1900);
WIRE 16 -1 (-950 1800)(-950 1850);
WIRE 16 -1 (-950 1850)(-750 1850);
WIRE 16 -1 (-950 1750)(-950 1800);
WIRE 16 -1 (-950 1800)(-750 1800);
WIRE 16 -1 (-950 1700)(-950 1750);
WIRE 16 -1 (-950 1750)(-750 1750);
WIRE 16 -1 (-950 1650)(-950 1700);
WIRE 16 -1 (-950 1700)(-750 1700);
WIRE 16 -1 (-950 1600)(-950 1650);
WIRE 16 -1 (-950 1650)(-750 1650);
WIRE 16 -1 (-950 1550)(-950 1600);
WIRE 16 -1 (-950 1600)(-750 1600);
WIRE 16 -1 (-950 1500)(-950 1550);
WIRE 16 -1 (-950 1550)(-750 1550);
WIRE 16 -1 (-950 1450)(-950 1500);
WIRE 16 -1 (-950 1500)(-750 1500);
WIRE 16 -1 (-950 1400)(-950 1450);
WIRE 16 -1 (-950 1450)(-750 1450);
WIRE 16 -1 (-950 1350)(-950 1400);
WIRE 16 -1 (-950 1400)(-750 1400);
WIRE 16 -1 (-950 1300)(-950 1350);
WIRE 16 -1 (-950 1350)(-750 1350);
WIRE 16 -1 (-950 1250)(-950 1300);
WIRE 16 -1 (-950 1300)(-750 1300);
WIRE 16 -1 (-950 1200)(-950 1250);
WIRE 16 -1 (-950 1250)(-750 1250);
WIRE 16 -1 (-950 1200)(-750 1200);
WIRE 16 -1 (-1100 2700)(-1100 2600);
WIRE 16 -1 (-1100 2600)(-950 2600);
WIRE 16 -1 (-950 2550)(-950 2600);
WIRE 16 -1 (-950 2600)(-750 2600);
WIRE 16 -1 (-950 2550)(-750 2550);
WIRE 16 -1 (2500 1150)(2500 1250);
WIRE 16 -1 (2500 1250)(2500 1300);
WIRE 16 -1 (2500 1250)(2300 1250);
WIRE 16 -1 (2500 1300)(2500 1350);
WIRE 16 -1 (2500 1300)(2300 1300);
WIRE 16 -1 (2500 1350)(2500 1400);
WIRE 16 -1 (2500 1350)(2300 1350);
WIRE 16 -1 (2500 1400)(2500 1450);
WIRE 16 -1 (2500 1400)(2300 1400);
WIRE 16 -1 (2500 1450)(2500 1500);
WIRE 16 -1 (2500 1450)(2300 1450);
WIRE 16 -1 (2500 1500)(2500 1550);
WIRE 16 -1 (2500 1500)(2300 1500);
WIRE 16 -1 (2500 1550)(2500 1600);
WIRE 16 -1 (2500 1550)(2300 1550);
WIRE 16 -1 (2500 1600)(2500 1650);
WIRE 16 -1 (2500 1600)(2300 1600);
WIRE 16 -1 (2500 1650)(2500 1700);
WIRE 16 -1 (2500 1650)(2300 1650);
WIRE 16 -1 (2500 1700)(2500 1750);
WIRE 16 -1 (2500 1700)(2300 1700);
WIRE 16 -1 (2500 1750)(2500 1800);
WIRE 16 -1 (2500 1750)(2300 1750);
WIRE 16 -1 (2500 1800)(2500 1850);
WIRE 16 -1 (2500 1800)(2300 1800);
WIRE 16 -1 (2500 1850)(2500 1900);
WIRE 16 -1 (2500 1850)(2300 1850);
WIRE 16 -1 (2500 1900)(2500 1950);
WIRE 16 -1 (2500 1900)(2300 1900);
WIRE 16 -1 (2500 1950)(2500 2000);
WIRE 16 -1 (2500 1950)(2300 1950);
WIRE 16 -1 (2500 2000)(2500 2050);
WIRE 16 -1 (2500 2000)(2300 2000);
WIRE 16 -1 (2500 2050)(2500 2100);
WIRE 16 -1 (2500 2050)(2300 2050);
WIRE 16 -1 (2500 2100)(2500 2150);
WIRE 16 -1 (2500 2100)(2300 2100);
WIRE 16 -1 (2500 2150)(2500 2200);
WIRE 16 -1 (2500 2150)(2300 2150);
WIRE 16 -1 (2500 2200)(2500 2250);
WIRE 16 -1 (2500 2200)(2300 2200);
WIRE 16 -1 (2500 2250)(2500 2300);
WIRE 16 -1 (2500 2250)(2300 2250);
WIRE 16 -1 (2500 2300)(2500 2350);
WIRE 16 -1 (2500 2300)(2300 2300);
WIRE 16 -1 (2500 2350)(2500 2400);
WIRE 16 -1 (2500 2350)(2300 2350);
WIRE 16 -1 (2500 2400)(2500 2450);
WIRE 16 -1 (2500 2400)(2300 2400);
WIRE 16 -1 (2500 2450)(2500 2500);
WIRE 16 -1 (2500 2450)(2300 2450);
WIRE 16 -1 (2500 2500)(2500 2550);
WIRE 16 -1 (2500 2500)(2300 2500);
WIRE 16 -1 (2500 2550)(2500 2600);
WIRE 16 -1 (2500 2550)(2300 2550);
WIRE 16 -1 (2500 2600)(2500 2650);
WIRE 16 -1 (2500 2600)(2300 2600);
WIRE 16 -1 (2500 2650)(2500 2700);
WIRE 16 -1 (2500 2650)(2300 2650);
WIRE 16 -1 (2500 2700)(2500 2750);
WIRE 16 -1 (2500 2700)(2300 2700);
WIRE 16 -1 (2500 2750)(2500 2800);
WIRE 16 -1 (2500 2750)(2300 2750);
WIRE 16 -1 (2500 2800)(2500 2850);
WIRE 16 -1 (2500 2800)(2300 2800);
WIRE 16 -1 (2500 2850)(2500 2900);
WIRE 16 -1 (2500 2850)(2300 2850);
WIRE 16 -1 (2500 2900)(2500 2950);
WIRE 16 -1 (2500 2900)(2300 2900);
WIRE 16 -1 (2500 2950)(2500 3000);
WIRE 16 -1 (2500 2950)(2300 2950);
WIRE 16 -1 (2500 3000)(2500 3050);
WIRE 16 -1 (2500 3000)(2300 3000);
WIRE 16 -1 (2500 3050)(2500 3100);
WIRE 16 -1 (2500 3050)(2300 3050);
WIRE 16 -1 (2500 3100)(2500 3150);
WIRE 16 -1 (2500 3100)(2300 3100);
WIRE 16 -1 (2500 3150)(2500 3200);
WIRE 16 -1 (2500 3150)(2300 3150);
WIRE 16 -1 (2500 3200)(2500 3250);
WIRE 16 -1 (2500 3200)(2300 3200);
WIRE 16 -1 (2500 3250)(2500 3300);
WIRE 16 -1 (2500 3250)(2300 3250);
WIRE 16 -1 (2500 3300)(2500 3350);
WIRE 16 -1 (2500 3300)(2300 3300);
WIRE 16 -1 (2500 3350)(2500 3400);
WIRE 16 -1 (2500 3350)(2300 3350);
WIRE 16 -1 (2500 3400)(2500 3450);
WIRE 16 -1 (2500 3400)(2300 3400);
WIRE 16 -1 (2500 3450)(2500 3500);
WIRE 16 -1 (2500 3450)(2300 3450);
WIRE 16 -1 (2500 3500)(2500 3550);
WIRE 16 -1 (2500 3500)(2300 3500);
WIRE 16 -1 (2500 3550)(2300 3550);
WIRE 16 -1 (-5150 1950)(-5150 1900);
WIRE 16 -1 (-3175 1950)(-5150 1950);
WIRE 16 -1 (-3175 1950)(-3175 2050);
WIRE 16 -1 (-3000 1950)(-3175 1950);
WIRE 16 -1 (-3175 2050)(-3000 2050);
WIRE 16 -1 (-4650 1450)(-4650 1350);
WIRE 16 -1 (-950 3025)(-950 2900);
WIRE 16 -1 (-950 2900)(-950 2850);
WIRE 16 -1 (-950 2900)(-750 2900);
WIRE 16 -1 (-950 2800)(-950 2850);
WIRE 16 -1 (-950 2850)(-750 2850);
WIRE 16 -1 (-950 2800)(-950 2750);
WIRE 16 -1 (-950 2800)(-750 2800);
WIRE 16 -1 (-950 2750)(-950 2700);
WIRE 16 -1 (-950 2750)(-750 2750);
WIRE 16 -1 (-950 2700)(-750 2700);
WIRE 16 -1 (-5150 2100)(-5150 2200);
WIRE 16 -1 (-5150 2100)(-3275 2100);
WIRE 16 -1 (-3275 2000)(-3275 2100);
WIRE 16 -1 (-3275 2100)(-3000 2100);
WIRE 16 -1 (-3000 2000)(-3275 2000);
WIRE 16 -1 (375 2900)(375 2975);
WIRE 16 -1 (375 2850)(375 2900);
WIRE 16 -1 (250 2900)(375 2900);
WIRE 16 -1 (250 2850)(375 2850);
WIRE 16 -1 (1100 1150)(1100 1250);
WIRE 16 -1 (1100 1250)(1100 1300);
WIRE 16 -1 (1100 1250)(1300 1250);
WIRE 16 -1 (1100 1300)(1100 1350);
WIRE 16 -1 (1100 1300)(1300 1300);
WIRE 16 -1 (1100 1350)(1100 1400);
WIRE 16 -1 (1100 1350)(1300 1350);
WIRE 16 -1 (1100 1400)(1100 1450);
WIRE 16 -1 (1100 1400)(1300 1400);
WIRE 16 -1 (1100 1450)(1100 1500);
WIRE 16 -1 (1100 1450)(1300 1450);
WIRE 16 -1 (1100 1500)(1100 1550);
WIRE 16 -1 (1100 1500)(1300 1500);
WIRE 16 -1 (1100 1550)(1100 1600);
WIRE 16 -1 (1100 1550)(1300 1550);
WIRE 16 -1 (1100 1600)(1100 1650);
WIRE 16 -1 (1100 1600)(1300 1600);
WIRE 16 -1 (1100 1650)(1100 1700);
WIRE 16 -1 (1100 1650)(1300 1650);
WIRE 16 -1 (1100 1700)(1100 1750);
WIRE 16 -1 (1100 1700)(1300 1700);
WIRE 16 -1 (1100 1750)(1100 1800);
WIRE 16 -1 (1100 1750)(1300 1750);
WIRE 16 -1 (1100 1800)(1100 1850);
WIRE 16 -1 (1100 1800)(1300 1800);
WIRE 16 -1 (1100 1850)(1100 1900);
WIRE 16 -1 (1100 1850)(1300 1850);
WIRE 16 -1 (1100 1900)(1100 1950);
WIRE 16 -1 (1100 1900)(1300 1900);
WIRE 16 -1 (1100 1950)(1100 2000);
WIRE 16 -1 (1100 1950)(1300 1950);
WIRE 16 -1 (1100 2000)(1100 2050);
WIRE 16 -1 (1100 2000)(1300 2000);
WIRE 16 -1 (1100 2050)(1100 2100);
WIRE 16 -1 (1100 2050)(1300 2050);
WIRE 16 -1 (1100 2100)(1100 2150);
WIRE 16 -1 (1100 2100)(1300 2100);
WIRE 16 -1 (1100 2150)(1100 2200);
WIRE 16 -1 (1100 2150)(1300 2150);
WIRE 16 -1 (1100 2200)(1100 2250);
WIRE 16 -1 (1100 2200)(1300 2200);
WIRE 16 -1 (1100 2250)(1100 2300);
WIRE 16 -1 (1100 2250)(1300 2250);
WIRE 16 -1 (1100 2300)(1100 2350);
WIRE 16 -1 (1100 2300)(1300 2300);
WIRE 16 -1 (1100 2350)(1100 2400);
WIRE 16 -1 (1100 2350)(1300 2350);
WIRE 16 -1 (1100 2400)(1100 2450);
WIRE 16 -1 (1100 2400)(1300 2400);
WIRE 16 -1 (1100 2450)(1100 2500);
WIRE 16 -1 (1100 2450)(1300 2450);
WIRE 16 -1 (1100 2500)(1100 2550);
WIRE 16 -1 (1100 2500)(1300 2500);
WIRE 16 -1 (1100 2550)(1100 2600);
WIRE 16 -1 (1100 2550)(1300 2550);
WIRE 16 -1 (1100 2600)(1100 2650);
WIRE 16 -1 (1100 2600)(1300 2600);
WIRE 16 -1 (1100 2650)(1100 2700);
WIRE 16 -1 (1100 2650)(1300 2650);
WIRE 16 -1 (1100 2700)(1100 2750);
WIRE 16 -1 (1100 2700)(1300 2700);
WIRE 16 -1 (1100 2750)(1100 2800);
WIRE 16 -1 (1100 2750)(1300 2750);
WIRE 16 -1 (1100 2800)(1100 2850);
WIRE 16 -1 (1100 2800)(1300 2800);
WIRE 16 -1 (1100 2850)(1100 2900);
WIRE 16 -1 (1100 2850)(1300 2850);
WIRE 16 -1 (1100 2900)(1100 2950);
WIRE 16 -1 (1100 2900)(1300 2900);
WIRE 16 -1 (1100 2950)(1100 3000);
WIRE 16 -1 (1100 2950)(1300 2950);
WIRE 16 -1 (1100 3000)(1100 3050);
WIRE 16 -1 (1100 3000)(1300 3000);
WIRE 16 -1 (1100 3050)(1100 3100);
WIRE 16 -1 (1100 3050)(1300 3050);
WIRE 16 -1 (1100 3100)(1100 3150);
WIRE 16 -1 (1100 3100)(1300 3100);
WIRE 16 -1 (1100 3150)(1100 3200);
WIRE 16 -1 (1100 3150)(1300 3150);
WIRE 16 -1 (1100 3200)(1100 3250);
WIRE 16 -1 (1100 3200)(1300 3200);
WIRE 16 -1 (1100 3250)(1100 3300);
WIRE 16 -1 (1100 3250)(1300 3250);
WIRE 16 -1 (1100 3300)(1100 3350);
WIRE 16 -1 (1100 3300)(1300 3300);
WIRE 16 -1 (1100 3350)(1100 3400);
WIRE 16 -1 (1100 3350)(1300 3350);
WIRE 16 -1 (1100 3400)(1100 3450);
WIRE 16 -1 (1100 3400)(1300 3400);
WIRE 16 -1 (1100 3450)(1100 3500);
WIRE 16 -1 (1100 3450)(1300 3450);
WIRE 16 -1 (1100 3500)(1100 3550);
WIRE 16 -1 (1100 3500)(1300 3500);
WIRE 16 -1 (1100 3550)(1300 3550);
WIRE 17 -1 (750 3475)(750 3575);
WIRE 17 -1 (750 3575)(750 3675);
WIRE 17 -1 (750 3675)(750 3775);
WIRE 17 -1 (750 3775)(750 3875);
WIRE 17 -1 (750 3875)(750 3975);
WIRE 17 -1 (750 3975)(750 4075);
WIRE 17 -1 (750 4075)(750 4175);
WIRE 17 -1 (750 4175)(750 4275);
WIRE 17 -1 (750 4275)(750 4375);
WIRE 17 -1 (750 4375)(750 4475);
WIRE 17 -1 (750 4475)(750 4575);
WIRE 17 -1 (750 4575)(750 4675);
WIRE 17 -1 (750 4675)(750 4775);
WIRE 17 -1 (750 4775)(750 4875);
WIRE 17 -1 (750 4875)(750 4975);
WIRE 17 -1 (750 4975)(750 5075);
WIRE 17 -1 (1550 5200)(750 5200);
FORCEPROP 2 LAST SIG_NAME M_L_DQS_DP<17:0>
J 0
(1000 5210);
DISPLAY 0.617021 (1000 5210);
PAINT ORANGE (1000 5210);
WIRE 17 -1 (750 5075)(750 5175);
WIRE 17 -1 (750 5175)(750 5200);
WIRE 17 -1 (1550 5150)(950 5150);
FORCEPROP 2 LAST SIG_NAME M_L_DQS_DN<17:0>
J 0
(1000 5160);
DISPLAY 0.617021 (1000 5160);
PAINT ORANGE (1000 5160);
WIRE 17 -1 (950 3425)(950 3525);
WIRE 17 -1 (950 3525)(950 3625);
WIRE 17 -1 (950 5125)(950 5150);
WIRE 17 -1 (950 5025)(950 5125);
WIRE 17 -1 (950 3625)(950 3725);
WIRE 17 -1 (950 3725)(950 3825);
WIRE 17 -1 (950 4925)(950 5025);
WIRE 17 -1 (950 4825)(950 4925);
WIRE 17 -1 (950 3825)(950 3925);
WIRE 17 -1 (950 3925)(950 4025);
WIRE 17 -1 (950 4725)(950 4825);
WIRE 17 -1 (950 4625)(950 4725);
WIRE 17 -1 (950 4025)(950 4125);
WIRE 17 -1 (950 4125)(950 4225);
WIRE 17 -1 (950 4525)(950 4625);
WIRE 17 -1 (950 4425)(950 4525);
WIRE 17 -1 (950 4225)(950 4325);
WIRE 17 -1 (950 4325)(950 4425);
WIRE 17 -1 (-1700 1775)(-1700 1825);
WIRE 17 -1 (-1700 1825)(-1700 1875);
WIRE 17 -1 (-1700 1875)(-1700 1925);
WIRE 17 -1 (-1700 1925)(-1700 1975);
WIRE 17 -1 (-1700 1975)(-1700 2025);
WIRE 17 -1 (-1700 2025)(-1700 2075);
WIRE 17 -1 (-1700 2075)(-1700 2125);
WIRE 17 -1 (-1700 2125)(-1700 2175);
WIRE 17 -1 (-1700 2175)(-1700 2225);
WIRE 17 -1 (-1700 2225)(-1700 2275);
WIRE 17 -1 (-1700 2275)(-1700 2325);
WIRE 17 -1 (-1700 2325)(-1700 2375);
WIRE 17 -1 (-1700 2375)(-1700 2425);
WIRE 17 -1 (-1700 2425)(-1700 2475);
WIRE 17 -1 (-1700 2475)(-1700 2525);
WIRE 17 -1 (-1700 2525)(-1700 2575);
WIRE 17 -1 (-1700 2575)(-1700 2625);
WIRE 17 -1 (-1700 2625)(-1700 2675);
WIRE 17 -1 (-1700 2675)(-1700 2725);
WIRE 17 -1 (-1700 2725)(-1700 2775);
WIRE 17 -1 (-1700 2775)(-1700 2825);
WIRE 17 -1 (-1700 2825)(-1700 2875);
WIRE 17 -1 (-1700 2875)(-1700 2925);
WIRE 17 -1 (-1700 2925)(-1700 2975);
WIRE 17 -1 (-1700 2975)(-1700 3025);
WIRE 17 -1 (-1700 3025)(-1700 3075);
WIRE 17 -1 (-1700 3075)(-1700 3125);
WIRE 17 -1 (-1700 3125)(-1700 3175);
WIRE 17 -1 (-1700 3175)(-1700 3225);
WIRE 17 -1 (-1700 3225)(-1700 3275);
WIRE 17 -1 (-1700 3275)(-1700 3325);
WIRE 17 -1 (-1700 3325)(-1700 3375);
WIRE 17 -1 (-1700 3375)(-1700 3425);
WIRE 17 -1 (-1700 3425)(-1700 3475);
WIRE 17 -1 (-1700 3475)(-1700 3525);
WIRE 17 -1 (-1700 3525)(-1700 3575);
WIRE 17 -1 (-1700 3575)(-1700 3625);
WIRE 17 -1 (-1700 3625)(-1700 3675);
WIRE 17 -1 (-1700 3675)(-1700 3725);
WIRE 17 -1 (-1700 3725)(-1700 3775);
WIRE 17 -1 (-1700 3775)(-1700 3825);
WIRE 17 -1 (-1700 3825)(-1700 3875);
WIRE 17 -1 (-1700 3875)(-1700 3925);
WIRE 17 -1 (-1700 3925)(-1700 3975);
WIRE 17 -1 (-1700 3975)(-1700 4025);
WIRE 17 -1 (-1700 4025)(-1700 4075);
WIRE 17 -1 (-1700 4075)(-1700 4125);
WIRE 17 -1 (-1700 4125)(-1700 4175);
WIRE 17 -1 (-1700 4175)(-1700 4225);
WIRE 17 -1 (-1700 4225)(-1700 4275);
WIRE 17 -1 (-1700 4275)(-1700 4325);
WIRE 17 -1 (-1700 4325)(-1700 4375);
WIRE 17 -1 (-1700 4375)(-1700 4425);
WIRE 17 -1 (-1700 4425)(-1700 4475);
WIRE 17 -1 (-1700 4475)(-1700 4525);
WIRE 17 -1 (-1700 4525)(-1700 4575);
WIRE 17 -1 (-1700 4575)(-1700 4625);
WIRE 17 -1 (-1700 4625)(-1700 4675);
WIRE 17 -1 (-1700 4675)(-1700 4725);
WIRE 17 -1 (-1700 4725)(-1700 4775);
WIRE 17 -1 (-1700 4775)(-1700 4825);
WIRE 17 -1 (-1700 4825)(-1700 4875);
WIRE 17 -1 (-1700 4875)(-1700 4925);
WIRE 17 -1 (-1225 4950)(-1700 4950);
FORCEPROP 2 LAST SIG_NAME M_L_DQ<63:0>
J 0
(-1660 4960);
DISPLAY 0.617021 (-1660 4960);
PAINT ORANGE (-1660 4960);
WIRE 17 -1 (-1700 4950)(-1700 4925);
WIRE 17 -1 (-3300 4075)(-3300 4125);
WIRE 17 -1 (-3300 4125)(-3300 4175);
WIRE 17 -1 (-3300 4175)(-3300 4225);
WIRE 17 -1 (-3300 4225)(-3300 4275);
WIRE 17 -1 (-3300 4275)(-3300 4325);
WIRE 17 -1 (-3300 4325)(-3300 4375);
WIRE 17 -1 (-3300 4375)(-3300 4425);
WIRE 17 -1 (-3300 4425)(-3300 4475);
WIRE 17 -1 (-3300 4475)(-3300 4525);
WIRE 17 -1 (-3300 4525)(-3300 4575);
WIRE 17 -1 (-3300 4575)(-3300 4625);
WIRE 17 -1 (-3300 4625)(-3300 4675);
WIRE 17 -1 (-3300 4675)(-3300 4725);
WIRE 17 -1 (-3300 4725)(-3300 4775);
WIRE 17 -1 (-3300 4775)(-3300 4825);
WIRE 17 -1 (-3800 4950)(-3300 4950);
FORCEPROP 2 LAST SIG_NAME M_L_MA<17:0>
J 0
(-3775 4960);
DISPLAY 0.617021 (-3775 4960);
PAINT ORANGE (-3775 4960);
WIRE 17 -1 (-3300 4925)(-3300 4950);
WIRE 17 -1 (-3300 4825)(-3300 4875);
WIRE 17 -1 (-3300 4875)(-3300 4925);
WIRE 17 -1 (-3300 3450)(-3800 3450);
FORCEPROP 2 LAST SIG_NAME M_L_CS_N<7:0>
J 0
(-3775 3460);
DISPLAY 0.617021 (-3775 3460);
PAINT ORANGE (-3775 3460);
WIRE 17 -1 (-3300 3425)(-3300 3450);
WIRE 17 -1 (-3300 3375)(-3300 3425);
WIRE 17 -1 (-3300 3325)(-3300 3375);
WIRE 17 -1 (-3300 3275)(-3300 3325);
WIRE 17 -1 (-3300 3200)(-3800 3200);
FORCEPROP 2 LAST SIG_NAME M_L_CKE<3:0>
J 0
(-3775 3210);
DISPLAY 0.617021 (-3775 3210);
PAINT ORANGE (-3775 3210);
WIRE 17 -1 (-3300 3175)(-3300 3200);
WIRE 17 -1 (-3300 3125)(-3300 3175);
WIRE 17 -1 (-3300 3050)(-3800 3050);
FORCEPROP 2 LAST SIG_NAME M_L_ODT<3:0>
J 0
(-3775 3060);
DISPLAY 0.617021 (-3775 3060);
PAINT ORANGE (-3775 3060);
WIRE 17 -1 (-3300 2975)(-3300 3025);
WIRE 17 -1 (-3300 3025)(-3300 3050);
WIRE 17 -1 (-3300 2525)(-3300 2575);
WIRE 17 -1 (-3300 2575)(-3300 2625);
WIRE 17 -1 (-3300 2625)(-3300 2675);
WIRE 17 -1 (-3300 2675)(-3300 2725);
WIRE 17 -1 (-3300 2725)(-3300 2775);
WIRE 17 -1 (-3300 2775)(-3300 2825);
WIRE 17 -1 (-3300 2900)(-3800 2900);
FORCEPROP 2 LAST SIG_NAME M_L_ECC<7:0>
J 0
(-3775 2910);
DISPLAY 0.617021 (-3775 2910);
PAINT ORANGE (-3775 2910);
WIRE 17 -1 (-3300 2825)(-3300 2875);
WIRE 17 -1 (-3300 2875)(-3300 2900);
WIRE 17 -1 (-3500 3700)(-3800 3700);
FORCEPROP 2 LAST SIG_NAME M_L_CLK_DN<3:0>
J 0
(-3800 3710);
DISPLAY 0.617021 (-3800 3710);
PAINT ORANGE (-3800 3710);
WIRE 17 -1 (-3500 3700)(-3500 3675);
WIRE 17 -1 (-3500 3675)(-3500 3575);
WIRE 17 -1 (-3300 3750)(-3800 3750);
FORCEPROP 2 LAST SIG_NAME M_L_CLK_DP<3:0>
J 0
(-3800 3760);
DISPLAY 0.617021 (-3800 3760);
PAINT ORANGE (-3800 3760);
WIRE 17 -1 (-3300 3725)(-3300 3750);
WIRE 17 -1 (-3300 3625)(-3300 3725);
WIRE 17 -1 (-3300 3925)(-3300 3975);
WIRE 17 -1 (-3300 4000)(-3800 4000);
FORCEPROP 2 LAST SIG_NAME M_L_BA<1:0>
J 0
(-3775 4010);
DISPLAY 0.617021 (-3775 4010);
PAINT ORANGE (-3775 4010);
WIRE 17 -1 (-3300 4000)(-3300 3975);
WIRE 17 -1 (-3300 3875)(-3800 3875);
FORCEPROP 2 LAST SIG_NAME M_L_BG<1:0>
J 0
(-3775 3885);
DISPLAY 0.617021 (-3775 3885);
PAINT ORANGE (-3775 3885);
WIRE 17 -1 (-3300 3825)(-3300 3875);
WIRE 16 -1 (850 3400)(450 3400);
WIRE 16 -1 (-3850 1650)(-3000 1650);
FORCEPROP 2 LAST SIG_NAME TP_CH_L_DIMM_L0_RFU_2
J 0
(-3800 1660);
DISPLAY 0.617021 (-3800 1660);
PAINT ORANGE (-3800 1660);
FORCEPROP 2 LASTPROP $XRERR UNIQUE?
J 0
(-4090 1650);
DISPLAY 0.638298 (-4090 1650);
PAINT MONO (-4090 1650);
DISPLAY INVISIBLE (-4090 1650);
WIRE 16 -1 (850 4400)(450 4400);
WIRE 16 -1 (-1800 4700)(-2000 4700);
WIRE 16 -1 (-1800 4650)(-2000 4650);
WIRE 16 -1 (-1800 3600)(-2000 3600);
WIRE 16 -1 (-3000 2200)(-4000 2200);
FORCEPROP 2 LAST SIG_NAME M_L_ACT_N
J 0
(-3950 2210);
DISPLAY 0.617021 (-3950 2210);
PAINT ORANGE (-3950 2210);
WIRE 16 -1 (-4750 1750)(-4650 1750);
WIRE 16 -1 (-4650 1750)(-4650 1650);
WIRE 16 -1 (-3000 1750)(-4650 1750);
FORCEPROP 2 LAST SIG_NAME M_L_VREF
J 0
(-3750 1760);
DISPLAY 0.617021 (-3750 1760);
PAINT ORANGE (-3750 1760);
WIRE 16 -1 (-3850 1550)(-3000 1550);
FORCEPROP 2 LAST SIG_NAME TP_CH_L_DIMM_L0_RFU_0
J 0
(-3800 1560);
DISPLAY 0.617021 (-3800 1560);
PAINT ORANGE (-3800 1560);
FORCEPROP 2 LASTPROP $XRERR UNIQUE?
J 0
(-4090 1550);
DISPLAY 0.638298 (-4090 1550);
PAINT MONO (-4090 1550);
DISPLAY INVISIBLE (-4090 1550);
WIRE 16 -1 (-3850 1600)(-3000 1600);
FORCEPROP 2 LAST SIG_NAME TP_CH_L_DIMM_L0_RFU_1
J 0
(-3800 1610);
DISPLAY 0.617021 (-3800 1610);
PAINT ORANGE (-3800 1610);
FORCEPROP 2 LASTPROP $XRERR UNIQUE?
J 0
(-4090 1600);
DISPLAY 0.638298 (-4090 1600);
PAINT MONO (-4090 1600);
DISPLAY INVISIBLE (-4090 1600);
WIRE 16 -1 (-3000 1900)(-3800 1900);
WIRE 16 -1 (-3800 1850)(-3000 1850);
FORCEPROP 2 LAST SIG_NAME SMB_DDR_KLM_VPP_SCL
J 0
(-3760 1860);
DISPLAY 0.617021 (-3760 1860);
PAINT ORANGE (-3760 1860);
WIRE 16 -1 (-3850 1450)(-3000 1450);
FORCEPROP 2 LAST SIG_NAME FM_ADR_COMPLETE_KLM_N
J 0
(-3800 1460);
DISPLAY 0.617021 (-3800 1460);
PAINT ORANGE (-3800 1460);
WIRE 16 -1 (-3450 2550)(-4175 2550);
FORCEPROP 2 LAST SIG_NAME FM_DIMM_EVENT_COD_N
J 0
(-4159 2572);
DISPLAY 0.617021 (-4159 2572);
PAINT ORANGE (-4159 2572);
WIRE 16 -1 (-3450 2300)(-3450 2550);
WIRE 16 -1 (-3450 2300)(-3000 2300);
WIRE 16 -1 (-3350 2850)(-3800 2850);
FORCEPROP 2 LAST SIG_NAME M_L_PAR
J 0
(-3775 2860);
DISPLAY 0.617021 (-3775 2860);
PAINT ORANGE (-3775 2860);
WIRE 16 -1 (-3350 2400)(-3350 2850);
WIRE 16 -1 (-3000 2400)(-3350 2400);
WIRE 16 -1 (-3400 2800)(-3800 2800);
FORCEPROP 2 LAST SIG_NAME M_KLM_RST_N
J 0
(-3775 2810);
DISPLAY 0.617021 (-3775 2810);
PAINT ORANGE (-3775 2810);
WIRE 16 -1 (-3400 2350)(-3400 2800);
WIRE 16 -1 (-3000 2350)(-3400 2350);
WIRE 16 -1 (-3175 3500)(-3800 3500);
FORCEPROP 2 LAST SIG_NAME M_L_C<2>
J 0
(-3775 3510);
DISPLAY 0.617021 (-3775 3510);
PAINT ORANGE (-3775 3510);
WIRE 16 -1 (-3175 3500)(-3175 3450);
WIRE 16 -1 (-3175 3450)(-3000 3450);
WIRE 16 -1 (-3000 3800)(-3200 3800);
WIRE 16 -1 (-3000 3850)(-3200 3850);
WIRE 16 -1 (-3000 3900)(-3200 3900);
WIRE 16 -1 (-3000 3950)(-3200 3950);
WIRE 16 -1 (-3000 3700)(-3200 3700);
WIRE 16 -1 (-3000 3650)(-3400 3650);
WIRE 16 -1 (-3000 3400)(-3200 3400);
WIRE 16 -1 (-3000 3600)(-3200 3600);
WIRE 16 -1 (-3000 3350)(-3200 3350);
WIRE 16 -1 (-3000 3300)(-3200 3300);
WIRE 16 -1 (-3000 4050)(-3200 4050);
WIRE 16 -1 (-3000 2800)(-3200 2800);
WIRE 16 -1 (-3000 2750)(-3200 2750);
WIRE 16 -1 (-3000 2700)(-3200 2700);
WIRE 16 -1 (-3000 2650)(-3200 2650);
WIRE 16 -1 (-3000 2600)(-3200 2600);
WIRE 16 -1 (-3000 2550)(-3200 2550);
WIRE 16 -1 (-3000 2500)(-3200 2500);
WIRE 16 -1 (-3000 3550)(-3400 3550);
WIRE 16 -1 (-3000 3150)(-3200 3150);
WIRE 16 -1 (-3000 2850)(-3200 2850);
WIRE 16 -1 (-3000 2950)(-3200 2950);
WIRE 16 -1 (-3000 3000)(-3200 3000);
WIRE 16 -1 (-3000 3100)(-3200 3100);
WIRE 16 -1 (-3000 3250)(-3200 3250);
WIRE 16 -1 (-3000 2250)(-4025 2250);
FORCEPROP 2 LAST SIG_NAME M_L_ALERT_N
J 0
(-3975 2260);
DISPLAY 0.617021 (-3975 2260);
PAINT ORANGE (-3975 2260);
WIRE 16 -1 (-1800 1750)(-2000 1750);
WIRE 16 -1 (-1800 1800)(-2000 1800);
WIRE 16 -1 (-1800 1850)(-2000 1850);
WIRE 16 -1 (-1800 1900)(-2000 1900);
WIRE 16 -1 (-1800 1950)(-2000 1950);
WIRE 16 -1 (-1800 2000)(-2000 2000);
WIRE 16 -1 (-1800 2300)(-2000 2300);
WIRE 16 -1 (-1800 2250)(-2000 2250);
WIRE 16 -1 (-1800 2200)(-2000 2200);
WIRE 16 -1 (-1800 2150)(-2000 2150);
WIRE 16 -1 (-1800 2100)(-2000 2100);
WIRE 16 -1 (-1800 2050)(-2000 2050);
WIRE 16 -1 (-1800 2550)(-2000 2550);
WIRE 16 -1 (-1800 2450)(-2000 2450);
WIRE 16 -1 (-1800 2400)(-2000 2400);
WIRE 16 -1 (-1800 2350)(-2000 2350);
WIRE 16 -1 (-1800 2500)(-2000 2500);
WIRE 16 -1 (-1800 2700)(-2000 2700);
WIRE 16 -1 (-1800 2800)(-2000 2800);
WIRE 16 -1 (-1800 2750)(-2000 2750);
WIRE 16 -1 (-1800 2650)(-2000 2650);
WIRE 16 -1 (-1800 2600)(-2000 2600);
WIRE 16 -1 (-1800 2850)(-2000 2850);
WIRE 16 -1 (-1800 2900)(-2000 2900);
WIRE 16 -1 (-1800 2950)(-2000 2950);
WIRE 16 -1 (-1800 3000)(-2000 3000);
WIRE 16 -1 (-1800 3050)(-2000 3050);
WIRE 16 -1 (-1800 3200)(-2000 3200);
WIRE 16 -1 (-1800 3150)(-2000 3150);
WIRE 16 -1 (-1800 3300)(-2000 3300);
WIRE 16 -1 (-1800 3250)(-2000 3250);
WIRE 16 -1 (-1800 3100)(-2000 3100);
WIRE 16 -1 (-1800 3400)(-2000 3400);
WIRE 16 -1 (-1800 3450)(-2000 3450);
WIRE 16 -1 (-1800 3350)(-2000 3350);
WIRE 16 -1 (-1800 3500)(-2000 3500);
WIRE 16 -1 (-1800 3550)(-2000 3550);
WIRE 16 -1 (-1800 3700)(-2000 3700);
WIRE 16 -1 (-1800 3800)(-2000 3800);
WIRE 16 -1 (-1800 3750)(-2000 3750);
WIRE 16 -1 (-1800 3650)(-2000 3650);
WIRE 16 -1 (-1800 3900)(-2000 3900);
WIRE 16 -1 (-1800 3950)(-2000 3950);
WIRE 16 -1 (-1800 4000)(-2000 4000);
WIRE 16 -1 (-1800 4050)(-2000 4050);
WIRE 16 -1 (-1800 3850)(-2000 3850);
WIRE 16 -1 (-3000 4100)(-3200 4100);
WIRE 16 -1 (-3000 4650)(-3200 4650);
WIRE 16 -1 (-3000 4700)(-3200 4700);
WIRE 16 -1 (-3000 4900)(-3200 4900);
WIRE 16 -1 (-3000 4200)(-3200 4200);
WIRE 16 -1 (-3000 4250)(-3200 4250);
WIRE 16 -1 (-3000 4300)(-3200 4300);
WIRE 16 -1 (-3000 4350)(-3200 4350);
WIRE 16 -1 (-3000 4400)(-3200 4400);
WIRE 16 -1 (-3000 4450)(-3200 4450);
WIRE 16 -1 (-3000 4500)(-3200 4500);
WIRE 16 -1 (-3000 4150)(-3200 4150);
WIRE 16 -1 (-3000 4550)(-3200 4550);
WIRE 16 -1 (-3000 4600)(-3200 4600);
WIRE 16 -1 (-3000 4750)(-3200 4750);
WIRE 16 -1 (-3000 4800)(-3200 4800);
WIRE 16 -1 (-3000 4850)(-3200 4850);
WIRE 16 -1 (-1800 4100)(-2000 4100);
WIRE 16 -1 (-1800 4150)(-2000 4150);
WIRE 16 -1 (-1800 4200)(-2000 4200);
WIRE 16 -1 (-1800 4250)(-2000 4250);
WIRE 16 -1 (-1800 4300)(-2000 4300);
WIRE 16 -1 (-1800 4350)(-2000 4350);
WIRE 16 -1 (-1800 4500)(-2000 4500);
WIRE 16 -1 (-1800 4550)(-2000 4550);
WIRE 16 -1 (-1800 4600)(-2000 4600);
WIRE 16 -1 (-1800 4450)(-2000 4450);
WIRE 16 -1 (-1800 4400)(-2000 4400);
WIRE 16 -1 (-1800 4800)(-2000 4800);
WIRE 16 -1 (-1800 4750)(-2000 4750);
WIRE 16 -1 (-1800 4850)(-2000 4850);
WIRE 16 -1 (-1800 4900)(-2000 4900);
WIRE 16 -1 (650 3450)(450 3450);
WIRE 16 -1 (850 3500)(450 3500);
WIRE 16 -1 (650 3550)(450 3550);
WIRE 16 -1 (850 3600)(450 3600);
WIRE 16 -1 (650 3650)(450 3650);
WIRE 16 -1 (850 3700)(450 3700);
WIRE 16 -1 (650 3750)(450 3750);
WIRE 16 -1 (850 3800)(450 3800);
WIRE 16 -1 (650 3850)(450 3850);
WIRE 16 -1 (850 3900)(450 3900);
WIRE 16 -1 (650 3950)(450 3950);
WIRE 16 -1 (850 4000)(450 4000);
WIRE 16 -1 (650 4050)(450 4050);
WIRE 16 -1 (650 4450)(450 4450);
WIRE 16 -1 (850 4500)(450 4500);
WIRE 16 -1 (650 4550)(450 4550);
WIRE 16 -1 (850 4600)(450 4600);
WIRE 16 -1 (650 4650)(450 4650);
WIRE 16 -1 (850 4700)(450 4700);
WIRE 16 -1 (650 4750)(450 4750);
WIRE 16 -1 (850 4800)(450 4800);
WIRE 16 -1 (650 4850)(450 4850);
WIRE 16 -1 (850 4900)(450 4900);
WIRE 16 -1 (650 4950)(450 4950);
WIRE 16 -1 (850 5000)(450 5000);
WIRE 16 -1 (650 5050)(450 5050);
WIRE 16 -1 (850 5100)(450 5100);
WIRE 16 -1 (850 4100)(450 4100);
WIRE 16 -1 (650 4150)(450 4150);
WIRE 16 -1 (850 4200)(450 4200);
WIRE 16 -1 (650 4250)(450 4250);
WIRE 16 -1 (850 4300)(450 4300);
WIRE 16 -1 (650 4350)(450 4350);
WIRE 16 -1 (650 5150)(450 5150);
DOT 1 (1100 3350);
DOT 1 (2500 2950);
DOT 1 (-950 2300);
DOT 1 (-950 2250);
DOT 1 (-950 2200);
DOT 1 (-950 2150);
DOT 1 (-950 2100);
DOT 1 (-950 1800);
DOT 1 (-950 1250);
DOT 1 (-950 1950);
DOT 1 (-950 1850);
DOT 1 (-3275 2100);
DOT 1 (-4650 1750);
DOT 1 (2500 3500);
DOT 1 (2500 3450);
DOT 1 (2500 3400);
DOT 1 (2500 3350);
DOT 1 (2500 3250);
DOT 1 (2500 3300);
DOT 1 (2500 3200);
DOT 1 (2500 3150);
DOT 1 (2500 3100);
DOT 1 (2500 3050);
DOT 1 (2500 3000);
DOT 1 (2500 2850);
DOT 1 (2500 2900);
DOT 1 (2500 2800);
DOT 1 (2500 2750);
DOT 1 (2500 2700);
DOT 1 (2500 2650);
DOT 1 (2500 2600);
DOT 1 (2500 2550);
DOT 1 (2500 2500);
DOT 1 (2500 2450);
DOT 1 (2500 2350);
DOT 1 (2500 2400);
DOT 1 (2500 2300);
DOT 1 (2500 2250);
DOT 1 (2500 2200);
DOT 1 (2500 2150);
DOT 1 (2500 2100);
DOT 1 (2500 2050);
DOT 1 (2500 1950);
DOT 1 (2500 2000);
DOT 1 (2500 1900);
DOT 1 (2500 1850);
DOT 1 (2500 1800);
DOT 1 (2500 1750);
DOT 1 (2500 1700);
DOT 1 (2500 1650);
DOT 1 (2500 1550);
DOT 1 (2500 1600);
DOT 1 (2500 1500);
DOT 1 (2500 1450);
DOT 1 (2500 1400);
DOT 1 (2500 1350);
DOT 1 (2500 1250);
DOT 1 (1100 3450);
DOT 1 (1100 3250);
DOT 1 (1100 3300);
DOT 1 (1100 3200);
DOT 1 (1100 3150);
DOT 1 (1100 3100);
DOT 1 (1100 3050);
DOT 1 (1100 3000);
DOT 1 (1100 2950);
DOT 1 (1100 2900);
DOT 1 (1100 2800);
DOT 1 (1100 2750);
DOT 1 (1100 2700);
DOT 1 (1100 2650);
DOT 1 (1100 2600);
DOT 1 (1100 2500);
DOT 1 (1100 2450);
DOT 1 (1100 2400);
DOT 1 (1100 2350);
DOT 1 (1100 2300);
DOT 1 (1100 2250);
DOT 1 (1100 2200);
DOT 1 (1100 2150);
DOT 1 (1100 2100);
DOT 1 (1100 2050);
DOT 1 (1100 2000);
DOT 1 (1100 1950);
DOT 1 (1100 1900);
DOT 1 (1100 1850);
DOT 1 (1100 1700);
DOT 1 (1100 1650);
DOT 1 (1100 1550);
DOT 1 (1100 1600);
DOT 1 (1100 1500);
DOT 1 (1100 1450);
DOT 1 (1100 1400);
DOT 1 (1100 1350);
DOT 1 (1100 1300);
DOT 1 (1100 1250);
DOT 1 (1100 3400);
DOT 1 (-950 2900);
DOT 1 (-950 2850);
DOT 1 (-950 2600);
DOT 1 (-950 2450);
DOT 1 (-950 2400);
DOT 1 (-950 2050);
DOT 1 (-950 2000);
DOT 1 (-950 1700);
DOT 1 (-950 1650);
DOT 1 (-950 1600);
DOT 1 (-950 1550);
DOT 1 (-950 1500);
DOT 1 (-950 1450);
DOT 1 (-950 1400);
DOT 1 (-950 1350);
DOT 1 (-950 1300);
DOT 1 (-950 2350);
DOT 1 (-950 1900);
DOT 1 (1100 2850);
DOT 1 (-950 2750);
DOT 1 (375 2900);
DOT 1 (-950 2800);
DOT 1 (1100 2550);
DOT 1 (1100 3500);
DOT 1 (1100 1800);
DOT 1 (-950 1750);
DOT 1 (-3175 1950);
DOT 1 (2500 1300);
DOT 1 (1100 1750);
FORCENOTE
PVDDQ (SINGLE SIDE) CAP: 10UF X1, 22UF X50
(-2950 5250) 0;
DISPLAY LEFT (-2950 5250);
DISPLAY 1.021277 (-2950 5250);
PAINT PURPLE (-2950 5250);
FORCENOTE
PVDDQ (DOUBLE SIDE) CAP: 100UF X8, 47UF X41
(-2950 5200) 0;
DISPLAY LEFT (-2950 5200);
DISPLAY 1.021277 (-2950 5200);
PAINT PURPLE (-2950 5200);
FORCENOTE
PLACE CAP NEAR DIMM CONNECTOR
(-5288 1202) 0;
DISPLAY LEFT (-5288 1202);
DISPLAY 1.595745 (-5288 1202);
PAINT PURPLE (-5288 1202);
FORCENOTE
SMBUS ADDR: 0XA4
(-2950 1159) 0;
DISPLAY LEFT (-2950 1159);
DISPLAY 1.957447 (-2950 1159);
PAINT PURPLE (-2950 1159);
FORCENOTE
PVPP CAP: 10UF X12
(-2950 5350) 0;
DISPLAY LEFT (-2950 5350);
DISPLAY 1.021277 (-2950 5350);
PAINT PURPLE (-2950 5350);
FORCENOTE
CAP BETWEEN DIMM
(-2950 5425) 0;
DISPLAY LEFT (-2950 5425);
DISPLAY 1.276596 (-2950 5425);
PAINT PURPLE (-2950 5425);
FORCENOTE
PVTT CAP: 100UF X2, 47UF X1
(-2950 5300) 0;
DISPLAY LEFT (-2950 5300);
DISPLAY 1.021277 (-2950 5300);
PAINT PURPLE (-2950 5300);
QUIT
